 
 
Open CloudServer  
OCS Chassis Management 
Specification Version 2.0 
 
 
 
 
 
Author: 
Badriddine Khessib, Director of Systems Software Development, Microsoft 
 



Open Compute Project  Open CloudServer OCS Chassis Management 
http://opencompute.org ii 
Revision History 
Date Description 
10/30/2014 Version 2.0 
 
  



Open Compute Project  Open CloudServer OCS Chassis Management 
http://opencompute.org iii 
 
© 2014 Microsoft Corporation. 
As of October 30, 2014, the following persons or entities have made this Specification available under the Open Web 
Foundation Final Specification Agreement (OWFa 1.0), which is available at http://www.openwebfoundation.org/legal/the-owf-
1-0-agreements/owfa-1-0 
 Microsoft Corporation.  
You can review the signed copies of the Open Web Foundation Agreement Version 1.0 for this Specification at 
http://opencompute.org/licensing/, which may also include additional parties to those listed above. 
Your use of this Specification may be subject to other third party rights. THIS SPECIFICATION IS PROVIDED "AS IS." The 
contributors expressly disclaim any warranties (express, implied, or otherwise), including implied warranties of merchantability, 
noninfringement, fitness for a particular purpose, or title, related to the Specification. The entire risk as to implementing or 
otherwise using the Specification is assumed by the Specification implementer and user. IN NO EVENT WILL ANY PARTY BE 
LIABLE TO ANY OTHER PARTY FOR LOST PROFITS OR ANY FORM OF INDIRECT, SPECIAL, INCIDENTAL, OR CONSEQUENTIAL 
DAMAGES OF ANY CHARACTER FROM ANY CAUSES OF ACTION OF ANY KIND WITH RESPECT TO THIS SPECIFICATION OR ITS 
GOVERNING AGREEMENT, WHETHER BASED ON BREACH OF CONTRACT, TORT (INCLUDING NEGLIGENCE), OR OTHERWISE, AND 
WHETHER OR NOT THE OTHER PARTY HAS BEEN ADVISED OF THE POSSIBILITY OF SUCH DAMAGE. 
CONTRIBUTORS AND LICENSORS OF THIS SPECIFICATION MAY HAVE MENTIONED CERTAIN TECHNOLOGIES THAT ARE MERELY 
REFERENCED WITHIN THIS SPECIFICATION AND NOT LICENSED UNDER THE OWF CLA OR OWFa. THE FOLLOWING IS A LIST OF 
MERELY REFERENCED TECHNOLOGY: INTELLIGENT PLATFORM MANAGEMENT INTERFACE (IPMI), I2C TRADEMARK OF PHILLIPS 
SEMICONDUCTOR. IMPLEMENTATION OF THESE TECHNOLOGIES MAY BE SUBJECT TO THEIR OWN LEGAL TERMS. 
  



 
iv October 30, 2014 
 
 
Contents 
1 Summary ....................................................................................................................................................... 1 
2 Chassis Manager ............................................................................................................................................ 1 
2.1 Chassis Manager Features ........................................................................................................................... 2 
2.2 Signal Interface ............................................................................................................................................ 4 
2.3 Blade Management ...................................................................................................................................... 9 
2.4 Power Control ............................................................................................................................................. 10 
2.4.1 Blade Power Control .............................................................................................................................. 10 
2.4.2 Remote Power Control .......................................................................................................................... 11 
2.5 Communication Ports ................................................................................................................................. 11 
2.6 Mechanical Specifications .......................................................................................................................... 12 
2.7 Chassis LEDs ............................................................................................................................................... 13 
2.7.1 Chassis Health Status LED ...................................................................................................................... 13 
2.7.2 Chassis Attention LED ............................................................................................................................ 14 
3 Systems Management Operations ............................................................................................................... 14 
3.1 Rack and Chassis Manager Commands...................................................................................................... 15 
3.2 In-Band Management Commands ............................................................................................................. 16 
3.3 Out-of-Band Management Commands ...................................................................................................... 18 
4 Chassis Manager Services ............................................................................................................................ 19 
4.1 Fan Control Protocol ................................................................................................................................... 20 
4.1.1 Determining Fan Speed ......................................................................................................................... 20 
4.1.2 Sample PWM Calculation ....................................................................................................................... 21 
4.2 Blade State Management .......................................................................................................................... 23 
4.3 Chassis Manager Component Failure Scenarios......................................................................................... 25 
5 Chassis Manager/Blade APIs ....................................................................................................................... 26 
5.1 Blade Implementation Requirements ......................................................................................................... 28 
5.1.1 IPMI Interfaces ....................................................................................................................................... 28 
5.1.2 IPMI Bus Support ................................................................................................................................... 28 
5.1.3 Intel® Node Manager ............................................................................................................................. 28 
5.1.4 BMC Debug Port .................................................................................................................................... 28 
5.1.5 BMC Bypass Jumper ............................................................................................................................... 28 
5.1.6 BMC Diagnostic Login ............................................................................................................................ 29 
5.1.7 IPMI Serial Session Login ....................................................................................................................... 29 
5.1.8 Serial Port Timeout ................................................................................................................................ 29 
5.1.9 Session Timeout ..................................................................................................................................... 29 
5.1.10 BMC Serial Port Baud Rate ................................................................................................................ 29 
5.1.11 Sensor Data Record ........................................................................................................................... 29 



Open Compute Project  Open CloudServer OCS Chassis Management 
http://opencompute.org v 
 
5.1.12 System Event Log ............................................................................................................................... 30 
5.1.13 Event Throttling ................................................................................................................................. 30 
5.1.14 Keyboard Controller Style Interface .................................................................................................. 30 
5.1.15 Serial Port Sharing ............................................................................................................................. 30 
5.1.16 Firmware Decompression ................................................................................................................. 31 
5.1.17 Inlet Sensor ........................................................................................................................................ 31 
5.2 Request and Response Packet Formats ...................................................................................................... 32 
5.3 Packet Framing .......................................................................................................................................... 33 
5.4 Serial Console Redirection .......................................................................................................................... 35 
5.5 Chassis Manager Serial Port Session .......................................................................................................... 36 
5.6 Command Completion Codes ..................................................................................................................... 37 
5.7 Blade Command Payload ........................................................................................................................... 39 
5.7.1 Blade Identification Commands ............................................................................................................. 40 
5.7.2 Session Establishment Commands ........................................................................................................ 40 
5.7.3 Session Termination .............................................................................................................................. 42 
5.8 Command Formats ..................................................................................................................................... 43 
5.8.1 Get Device ID ......................................................................................................................................... 43 
5.8.2 Get System GUID ................................................................................................................................... 43 
5.8.3 Get Channel Authentication Capabilities ............................................................................................... 43 
5.8.4 Get Session Challenge ............................................................................................................................ 46 
5.8.5 Activate Session ..................................................................................................................................... 46 
5.8.6 Set Session Privilege Level ..................................................................................................................... 46 
5.8.7 Close Session .......................................................................................................................................... 46 
5.8.8 Get Message .......................................................................................................................................... 46 
5.8.9 Send Message ........................................................................................................................................ 46 
5.8.10 Get Chassis Status ............................................................................................................................. 46 
5.8.11 Chassis Control .................................................................................................................................. 46 
5.8.12 Chassis Identify .................................................................................................................................. 46 
5.8.13 Set Power Restore Policy ................................................................................................................... 46 
5.8.14 Set Power Cycle Interval .................................................................................................................... 47 
5.8.15 Set System Boot Options ................................................................................................................... 47 
5.8.16 Get System Boot Options .................................................................................................................. 47 
5.8.17 Get Sensor Reading Factors ............................................................................................................... 47 
5.8.18 Get Sensor Reading ........................................................................................................................... 47 
5.8.19 Get Sensor Type ................................................................................................................................ 47 
5.8.20 Read FRU Data ................................................................................................................................... 47 
5.8.21 Write FRU Data .................................................................................................................................. 47 
5.8.22 Reserve SDR Repository .................................................................................................................... 47 
5.8.23 Get SDR .............................................................................................................................................. 47 
5.8.24 Reserve SEL ........................................................................................................................................ 47 
5.8.25 Get SEL Entry ..................................................................................................................................... 48 
5.8.26 Add SEL Entry..................................................................................................................................... 48 
5.8.27 Clear SEL ............................................................................................................................................ 48 



 
vi October 30, 2014 
 
5.8.28 Set Serial/Modem Mux ..................................................................................................................... 48 
5.8.29 Get Power Reading ............................................................................................................................ 48 
5.8.30 Get Power Limit ................................................................................................................................. 48 
5.8.31 Set Power Limit.................................................................................................................................. 48 
5.8.32 Activate Power Limit ......................................................................................................................... 48 
5.8.33 Get Processor Info ............................................................................................................................. 49 
5.8.34 Get Memory Info ............................................................................................................................... 50 
5.8.35 Get PCIe Info ...................................................................................................................................... 51 
5.8.36 Get NIC Info ....................................................................................................................................... 52 
5.8.37 BMC Debug ........................................................................................................................................ 53 
5.8.38 Get BIOS Code ................................................................................................................................... 53 
5.8.39 Get Disk Status .................................................................................................................................. 54 
5.8.40 Get Disk Info ...................................................................................................................................... 55 
5.8.41 Network Controller BIOS Integration ................................................................................................ 56 
5.8.42 Sensor Data Repository ..................................................................................................................... 56 
5.8.43 Hardcoded Sensor Numbers ............................................................................................................. 59 
6 Chassis Manager REST API ........................................................................................................................... 60 
6.1 User Roles and API Access .......................................................................................................................... 60 
6.2 Encryption and Service Credentials ............................................................................................................ 60 
6.3 Client Credentials/Authentication .............................................................................................................. 60 
6.4 Role-Based API-Level Authorization ........................................................................................................... 60 
6.5 REST API: Response and Completion Codes ............................................................................................... 64 
6.6 REST API: Descriptions, Usage Scenarios, and Sample Responses ............................................................. 64 
6.6.1 Gets Information about Chassis............................................................................................................ 65 
6.6.2 Gets Information about Blade .............................................................................................................. 68 
6.6.3 Gets Information about All Blades ....................................................................................................... 69 
6.6.4 Turns Chassis Attention LED ON ........................................................................................................... 71 
6.6.5 Turns Chassis Attention LED OFF .......................................................................................................... 72 
6.6.6 Gets Chassis Attention LED Status ........................................................................................................ 72 
6.6.7 Turns Blade Attention LED ON .............................................................................................................. 73 
6.6.8 Turns All Blade Attention LEDs ON ....................................................................................................... 73 
6.6.9 Turns Blade Attention LED OFF ............................................................................................................. 74 
6.6.10 Turns All Blade Attention LEDs OFF ................................................................................................. 75 
6.6.11 Sets Default Blade Power State ON ................................................................................................. 76 
6.6.12 Sets Default Power State of All Blades ON ...................................................................................... 77 
6.6.13 Sets Default Blade Power State OFF ................................................................................................ 78 
6.6.14 Sets Default Power State of All Blades OFF ..................................................................................... 79 
6.6.15 Gets Default Blade Power State ....................................................................................................... 80 
6.6.16 Gets the Default Power State of All Blades...................................................................................... 80 
6.6.17 Gets Outlet Power State of Blade .................................................................................................... 82 
6.6.18 Gets AC Outlet Power State of All Blades ........................................................................................ 82 
6.6.19 Turns AC Outlet Power ON for Blade ............................................................................................... 84 
6.6.20 Turns the AC Outlet Power ON for All Blades .................................................................................. 84 



Open Compute Project  Open CloudServer OCS Chassis Management 
http://opencompute.org vii 
 
6.6.21 Turns AC Outlet Power OFF for Blade .............................................................................................. 85 
6.6.22 Turns AC Outlet Power OFF for All Blades ....................................................................................... 86 
6.6.23 Gets the ON/OFF State of Blade ....................................................................................................... 87 
6.6.24 Gets the ON/OFF State of All Blades ................................................................................................ 88 
6.6.25 Supplies Power to the Blade Chipset ............................................................................................... 89 
6.6.26 Supplies Power to All Blade Chipsets ............................................................................................... 90 
6.6.27 Stops Power to Blade Chipset .......................................................................................................... 91 
6.6.28 Stops Power to All Blade Chipsets .................................................................................................... 91 
6.6.29 Power Cycle Blade ............................................................................................................................ 93 
6.6.30 Power Cycle All Blades ...................................................................................................................... 93 
6.6.31 Turns Chassis AC Sockets (TOR Switches) ON .................................................................................. 94 
6.6.32 Turns Chassis AC Sockets (TOR Switches) OFF ................................................................................. 95 
6.6.33 Gets Status of Chassis AC Sockets (TOR Switches) .......................................................................... 95 
6.6.34 Starts Serial Session to Blade ........................................................................................................... 96 
6.6.35 Stop Serial Session to Blade ............................................................................................................. 97 
6.6.36 Sends Data to Blade Serial Device .................................................................................................... 97 
6.6.37 Receives Data from Blade ................................................................................................................. 98 
6.6.38 Starts Serial Port Console ................................................................................................................. 98 
6.6.39 Stops Serial Port Console .................................................................................................................. 99 
6.6.40 Sends Serial Port Data ...................................................................................................................... 99 
6.6.41 Receives Serial Port Data ................................................................................................................ 100 
6.6.42 Reads the Chassis Log (with timestamp parameter) ..................................................................... 100 
6.6.43 Clears the Chassis Log ..................................................................................................................... 101 
6.6.44 Reads Log from Blade (with timestamp parameter) ..................................................................... 102 
6.6.45 Clears Log from Blade ..................................................................................................................... 103 
6.6.46 Gets Power Reading from Blade .................................................................................................... 103 
6.6.47 Gets Power Readings from All Blades ............................................................................................ 104 
6.6.48 Gets Power Limit of Blade .............................................................................................................. 105 
6.6.49 Gets Power Limit of All Blades ....................................................................................................... 106 
6.6.50 Sets Power Limit on Blade .............................................................................................................. 108 
6.6.51 Sets Power Limit on All Blades ....................................................................................................... 108 
6.6.52 Activates Blade Power Limit ........................................................................................................... 109 
6.6.53 Activates Power Limit on All Blades ............................................................................................... 110 
6.6.54 Deactivates Blade Power Limit ....................................................................................................... 111 
6.6.55 Deactivates Power Limit on All Blades ........................................................................................... 111 
6.6.56 Gets Chassis Controller Network Properties .................................................................................. 112 
6.6.57 Adds New Chassis Controller User ................................................................................................. 113 
6.6.58 Changes Password for Existing Chassis Controller User ................................................................ 114 
6.6.59 Changes Role for Existing Chassis Controller User ......................................................................... 114 
6.6.60 Removes Existing Chassis Controller User ..................................................................................... 115 
6.6.61 Get Health of Chassis ...................................................................................................................... 115 
3.62 Get Health of Blade .................................................................................................................................. 118 
6.6.62 Get Next Boot Device ..................................................................................................................... 120 
6.6.63 Set Next Boot Device ...................................................................................................................... 120 
6.6.64 Get Service Version ......................................................................................................................... 121 
6.6.65 Reset PSU ........................................................................................................................................ 122 



 
viii October 30, 2014 
 
6.6.66 Get Chassis Manager Asset Info ...................................................................................................... 122 
6.6.67 Get Power Distribution Board (PDB) Asset Info .............................................................................. 123 
6.6.68 Get Blade Asset Info ........................................................................................................................ 123 
6.6.69 Set Chassis Manager Asset Info ....................................................................................................... 124 
6.6.70 Set PDB Asset Info ........................................................................................................................... 124 
6.6.71 Set Blade Asset Info ......................................................................................................................... 124 
6.6.72 Get Blade Post Code ........................................................................................................................ 125 
6.6.73 Update PSU Firmware ..................................................................................................................... 125 
6.6.74 Get PSU Firmware Update Status .................................................................................................... 126 
7 Command Line Interface ........................................................................................................................... 126 
7.1 Install the Chassis Manager Service ......................................................................................................... 126 
7.2 State and Information Commands ........................................................................................................... 127 
7.2.1 GetChassisInfo ..................................................................................................................................... 127 
7.2.2 GetBladeInfo ....................................................................................................................................... 129 
7.2.3 GetChassisHealth ................................................................................................................................ 129 
7.2.4 GetBladeHealth ................................................................................................................................... 132 
7.2.5 GetServiceVersion ............................................................................................................................... 134 
7.2.6 Update PSU Firmware ......................................................................................................................... 134 
7.2.7 Get PSU Firmware Update Status ....................................................................................................... 135 
7.3 Blade Management Commands ............................................................................................................... 136 
7.3.1 SetPowerOn ........................................................................................................................................ 136 
7.3.2 SetPowerOff ........................................................................................................................................ 136 
7.3.3 GetPowerState .................................................................................................................................... 137 
7.3.4 SetBladeOn .......................................................................................................................................... 137 
7.3.5 SetBladeOff ......................................................................................................................................... 138 
7.3.6 GetBladeState ..................................................................................................................................... 138 
7.3.7 SetBladeDefaultPowerState ............................................................................................................... 138 
7.3.8 GetBladeDefaultPowerState ............................................................................................................... 139 
7.3.9 SetBladeActivePowerCycle ................................................................................................................. 139 
7.3.10 SetBladeAttentionLEDOn ............................................................................................................... 140 
7.3.11 SetBladeAttentionLEDOff ............................................................................................................... 140 
7.3.12 ReadBladeLog ................................................................................................................................. 141 
7.3.13 ClearBladeLog ................................................................................................................................. 141 
7.3.14 SetBladePowerLimit ....................................................................................................................... 142 
7.3.15 SetBladePowerLimitOn ................................................................................................................... 142 
7.3.16 SetBladePowerLimitOff .................................................................................................................. 143 
7.3.17 GetBladePowerLimit ....................................................................................................................... 143 
7.3.18 GetBladePowerReading .................................................................................................................. 143 
7.3.19 GetNextBoot ................................................................................................................................... 144 
7.3.20 SetNextBoot .................................................................................................................................... 144 
7.3.21 GetBladeAssetInfo .......................................................................................................................... 145 
7.3.22 SetBladeAssetInfo ........................................................................................................................... 146 
7.3.23 GetPDBAssetInfo ............................................................................................................................ 146 
7.3.24 SetPDBAssetInfo ............................................................................................................................. 147 



Open Compute Project  Open CloudServer OCS Chassis Management 
http://opencompute.org ix 
 
7.3.25 GetBladeBIOSPostCode .................................................................................................................. 148 
7.4 Chassis Manager Management Commands ............................................................................................ 148 
7.4.1 SetChassisAttentionLEDOn ................................................................................................................. 148 
7.4.2 SetChassisAttentionLEDOff ................................................................................................................. 149 
7.4.3 GetChassisAttentionLEDStatus ........................................................................................................... 149 
7.4.4 ReadChassisLog ................................................................................................................................... 149 
7.4.5 ClearChassisLog ................................................................................................................................... 150 
7.4.6 GetACSocketPowerState ..................................................................................................................... 151 
7.4.7 SetACSocketPowerStateOn ................................................................................................................ 151 
7.4.8 SetACSocketPowerStateOff ................................................................................................................ 152 
7.4.9 AddChassisControllerUser .................................................................................................................. 152 
7.4.10 ChangeChassisControllerUserPassword ......................................................................................... 153 
7.4.11 ChangeChassisControllerUserRole ................................................................................................. 153 
7.4.12 RemoveChassisControllerUser ....................................................................................................... 153 
7.4.13 GetChassisManagerAssetInfo ......................................................................................................... 154 
7.4.14 SetChassisManagerAssetInfo ......................................................................................................... 155 
7.5 Blade and Serial Console Session Commands........................................................................................... 156 
7.5.1 StartBladeSerialSession ...................................................................................................................... 156 
7.5.2 StopBladeSerialSession ....................................................................................................................... 156 
7.5.3 StartPortSerialSession ......................................................................................................................... 157 
7.5.4 StopPortSerialSession ......................................................................................................................... 157 
7.5.5 EstablishCmConnection ...................................................................................................................... 158 
7.5.6 TerminateCmConnection .................................................................................................................... 159 
7.6 CLI Over Serial (WCSCLI+) ......................................................................................................................... 159 
7.6.1 StartChassisManager .......................................................................................................................... 159 
7.6.2 StopChassisManager ........................................................................................................................... 159 
7.6.3 GetChassisManagerStatus .................................................................................................................. 160 
7.6.4 EnableChassisManagerSsl ................................................................................................................... 160 
7.6.5 DisableChassisManagerSsl .................................................................................................................. 161 
7.6.6 GetNetworkProperties (getnic) .......................................................................................................... 161 
7.6.7 SetNetworkProperties (setnic) ........................................................................................................... 162 
7.6.8 Clear ..................................................................................................................................................... 163 
7.7 PuTTY Settings for serial connection ........................................................................................................ 163 
7.8 Service Install............................................................................................................................................ 168 
 
  



 
x October 30, 2014 
 
Table of Figures 
Figure 1: CAD representation of the Chassis Manager ................................................................................. 1 
Figure 2: Top level representation of Chassis Manager ............................................................................... 2 
Figure 3: Chassis manager hardware block diagram .................................................................................... 3 
Figure 4: Blade management connectivity ................................................................................................. 10 
Figure 5: Chassis manager dimensions and edge finger locations ............................................................. 13 
Figure 6: Chassis manager services ............................................................................................................. 19 
Figure 7: Blade state management ............................................................................................................. 24 
Figure 8: Serial port sharing mux diagram .................................................................................................. 31 
Figure 9: Request packet format ................................................................................................................ 32 
Figure 10: Response packet format ............................................................................................................ 32 
Figure 11: Message payload encapsulated with the serial start and stop bytes ........................................ 35 
Figure 12: Chassis Manager payload........................................................................................................... 39 
Figure 13: Session establishment process .................................................................................................. 41 
Figure 14: Set assigned baud rate ............................................................................................................. 164 
Figure 15: Set terminal settings ................................................................................................................ 165 
Figure 16: Set keyboard and backspace settings ...................................................................................... 166 
Figure 17: Set window size ........................................................................................................................ 167 
Figure 18: Save settings ............................................................................................................................ 168 
 
  



Open Compute Project  Open CloudServer OCS Chassis Management 
http://opencompute.org xi 
 
Table of Tables 
Table 1: PDB connector interface (J18) ......................................................................................................... 4 
Table 2: PDB connector interface (J35) ......................................................................................................... 7 
Table 3: Serial RJ-45 cable definition for ports 1 and 2 .............................................................................. 11 
Table 4: Serial RJ-45 cable definition for ports 5 and 6 .............................................................................. 12 
Table 5: Chassis health status LED description ........................................................................................... 13 
Table 6: Chassis Attention LED description................................................................................................. 14 
Table 7: Rack infrastructure command functionality ................................................................................. 15 
Table 8: Command functionality supported by in-band path ..................................................................... 17 
Table 9: Command functionality supported by out-of-band path.............................................................. 18 
Table 10: Chassis manager services ............................................................................................................ 19 
Table 11: Input and output for fan control software .................................................................................. 20 
Table 12: Input and output for fan control software .................................................................................. 21 
Table 13: Example sensor readings ............................................................................................................. 22 
Table 14: Blade states ................................................................................................................................. 24 
Table 15: Required IPMI fields for blades ................................................................................................... 26 
Table 16: Details for Request and Response Packets ................................................................................. 32 
Table 17: Special characters used for packet framing ................................................................................ 33 
Table 18: Encoding sequences for special characters................................................................................. 34 
Table 19: Conditions causing switching ...................................................................................................... 36 
Table 20: Command-completion codes ...................................................................................................... 37 
Table 21: Get channel authentication capabilities command request ....................................................... 43 
Table 22: Get channel authentication capabilities command response..................................................... 44 
Table 23: Get Processor Info request ......................................................................................................... 49 
Table 24: Get Processor Info response ....................................................................................................... 49 
Table 25: Processor types ........................................................................................................................... 49 
Table 26. Get Memory Info response (if zero index as DIMM index) ......................................................... 50 
Table 27: Get Memory Info request ........................................................................................................... 50 
Table 28: Get Memory Info response (1+ index as DIMM index) ............................................................... 51 
Table 29: PCIe slot mapping ........................................................................................................................ 51 
Table 30: Get PCIe Info request .................................................................................................................. 52 
Table 31: Get PCIe Info response ................................................................................................................ 52 
Table 32: Get PCIe Info response ................................................................................................................ 52 
Table 33: Get NIC Info request .................................................................................................................... 53 
Table 34: Get NIC Info response ................................................................................................................. 53 
Table 35: BMC Debug request .................................................................................................................... 53 
Table 36: BMC Debug response .................................................................................................................. 53 
Table 37: Get BIOS Code request ................................................................................................................ 54 
Table 38: Get BIOS Code response ............................................................................................................. 54 
Table 39: Get Disk Status request ............................................................................................................... 54 
Table 40: Get Disk Status response ............................................................................................................. 55 



 
xii October 30, 2014 
 
Table 41: Get Disk Info request ................................................................................................................... 55 
Table 42: Get Disk Info response ................................................................................................................ 55 
Table 43. Sample SDR: ................................................................................................................................ 57 
Table 44: Hardcoded sensor numbers: ....................................................................................................... 59 
Table 45: Chassis manager APIs and corresponding authorized roles ....................................................... 61 
Table 46: Commands to install Chassis Manager service and launch the CLI........................................... 126 



 
http://opencompute.org 1 
 
1 Summary 
This specification, Open CloudServer Chassis Management Version 2.0, describe systems 
management for the Open CloudServer (OCS) system. System management uses the Chassis 
Manager (CM) to present a consistent, optimized interface for the complete rack infrastructure, 
including the in-band and out-of-band (OOB) management paths. 
The Chassis Manager provides the front end through an applications interface (RESTful web API) for 
automated management and through a command-line interface (CLI) for manual management. The 
Chassis Manager manages all devices within the rack and communicates directly with the blade 
management system through a serial multiplexor. 
2 Chassis Manager 
The Chassis Manager printed circuit board assembly (PCBA) is a general-purpose processing 
assembly integrated into the plenum of the chassis and attaching directly to the Power Distribution 
Backplane (PDB).  The Chassis Manager communicates directly with the server blades and provides 
management for all devices within the rack, including power supplies and fans. Figure 1 shows a 
CAD representation of the Chassis Manager. 
 
Figure 1: CAD representation of the Chassis Manager 


 
2 October 30, 2014 
 
2.1 Chassis Manager Features 
The Chassis Manager features include: 
 Input/Output (I/O): 
o 2 x 1GbE Ethernet (general purpose to be used for network access or for direct 
connector to the top-of-rack [TOR] management ports) 
o 4 x RS-232 (network switch management for boot strap initial start-up) 
o Remote power control (one input signal, three output signals to the power distribution 
unit [PDU] or to another Chassis Manager for remote power control) 
 Windows Server 2012 R2 operating system 
 Hot repair, no downtime during replacement 
 Server hardware 
o Embedded x86 processor 
o Memory—4GB with error-correcting code (ECC) 
o Storage—64GB solid-state drive (SSD) 
o Trusted Platform Module—enabling a secure solution 
o Embedded serial multiplexor for hard-wired communication to blades 
o Blade power on/off signals hard-wired for definitive control of blade power 
Figure 2 shows a top-level representation of the Chassis Manager, trays, power supply units, and 
fans. 
Chassis Management
General purpose and highly flexible
Chassis        
Fan Tray
PSUs
1 .. 6
Tray
1 .. 12
Chassis Manager
Windows Server 2012
Serial Management
Power Control
PSU Monitoring
Fan Control and Monitoring
2 x 1GbE
General 
Purpose
4 x RS232
NWK Switch 
Management
Power Control
3 x Outputs
1 x Input
 
Figure 2: Top level representation of Chassis Manager 



Open Compute Project  Open CloudServer OCS Chassis Management 
http://opencompute.org 3 
 
Figure 3 shows the hardware block diagram for the Chassis Manager. 
  Chassis Manager  (CM)
Tray1_Blade_EN[3:0]
Tray2_Blade_EN[3:0]
Tray3_Blade_EN[3:0]
Tray4_Blade_EN[3:0]
Fan PWM
CMC_Fan Tach[4:1]
Fan Ctl 
ADT740
0x5Eh
6 PSU 
6 PSU 
6 PSU 
6 PSU 
6 PSU 
6 Fans
Tray5_Blade_EN[3:0]
Tray6_Blade_EN[3:0]
Tray7_Blade_EN[3:0]
Tray8_Blade_EN[3:0]
Tray9_Blade_EN[3:0]
Tray10_Blade_EN[3:0]
Tray11_Blade_EN[3:0]
Tray12_Blade_EN[3:0]
PCA9535C
GPIO
0x40h
PCA9535C
GPIO
0x42h
PCA9535C
GPIO
0x44h
X86 SoC
CM FRU EEPROM
0xA0h
 Fan Ctl 
ADT7470
0x58h
CMC_Fan Tach[5:6]
CPLD_3
Altera
EPM240
1
2
 
23
24
          RST   RX/TX
Tray7_Node1_TX/RX
Tray7_Node2_TX/RX
Tray12_Node3_TX/RX
Tray12_Node4_TX/RX
PCA9535C
GPIO
0x48h
PCA9516
I2C Hub
PMBus1
6 PSU 
PSU 1..2
6 PSU 
PSU 3..4
6 PSU 
PSU 5..6
PMBus2
PMBus3
AC_OK[6:1]
DC_OK[6:1]
Attention LED
Status LED
PCA9535C
GPIO
0x4Ah
PSU_PS_ON[6:1]
PCA_CPLD_WDT2
Power Switch[2:0]
CPLD_FAN_MAX
CPLD_WDT[1,3]
WDT_ENABLE_N
UART_SW_S[0:5]_N
CMC_CPU_RST_N
CPLD_EXT_RST_N
CMC_RESERVE_1
FAN_MAX_CTR
CPLD_FAN_MAX
PMB_EN_[1:3]
CPLD_2
Altera
EPM240
1
2
 
23
24
RST   RX/TX              .
Tray1_Node1_TX/RX
Tray1_Node2_TX/RX
Tray6_Node3_TX/RX
Tray6_Node4_TX/RX
WDT_LED
PSU_ALERT_N
CPLD_THRMTRIP_LOG_N
PCA9535_INT_N
SC18IM700
(RS232 to I2C)
PMB_EN_1
PMB_EN_2
PMB_EN_3
PCA9535_INT_N
FAN_MAX_CTR
CPLD_WDT_1
CPU_RST_N
CMC_RESERVE_1
GPIO0
GPIO1
GPIO2
GPIO3
GPIO4
GPIO5
GPIO6
GPIO7
RST#          TX/RX
I2C
SC18IM700
(Serial Mux Ctrl)
GPIO0
GPIO1
GPIO2
GPIO3
GPIO4
GPIO5
GPIO6
GPIO7
RST#          TX/RX
 UART_SW_S0_N
UART_SW_S1_N
UART_SW_S2_N
UART_SW_S3_N
UART_SW_S4_N
UART_SW_S5_N
WDT_EN_N
CABLE_DETECT_N
COM4
TX/RX
RI
RTS
DTR
PDB
1GbE
RJ45
(metal)
COM1 
RJ45 
(plastic)
COM2 
RJ45 
(plastic)
COM5 
RJ45 
(plastic)
1GbE
RJ45
(metal)
COM6 
RJ45 
(plastic)
ON/OFF 
output
ON/OFF 
CM input
ON/OFF 
output
ON/OFF 
ouput
COM3RI
RTS
DTR
TX/RX
 
Figure 3: Chassis manager hardware block diagram 



 
4 October 30, 2014 
 
2.2 Signal Interface 
The Chassis Manager interfaces to the power distribution board through two PCIe x16 connectors. 
Table 1 and Table 2 show the pinout information for these connectors. Refer to the schematics for 
connector reference designators. 
Table 1 shows the pinout for the J18 PDB connector interface. 
Table 1: PDB connector interface (J18) 
Pin Signal Pin Signal 
B1 GND A1 GND 
B2 LAN2_P1_P A2 GND 
B3 LAN2_P1_N A3 LAN2_P3_P 
B4 GND A4 LAN2_P3_N 
B5 LAN2_P2_P A5 GND 
B6 LAN2_P2_N A6 LAN2_P4_P 
B7 GND A7 LAN2_P4_N 
B8 GND A8 GND 
B9 GND A9 POWER_SW3_PWR_CTR_12V 
B10 I2C_PDB_SCL A10 POWER_SW2_PWR_CTR_12V 
B11 I2C_PDB_SDA A11 POWER_SW1_PWR_CTR_12V 
B12 P3V3_NODE1 A12 NC 
B13 NC A13 NC 
B14 NC A14 NC 
B15 NC A15 NC 
B16 NC A16 NC 
B17 NC A17 GND 
B18 GND A18 UART_RTS_RP6_L_N 
B19 UART_RTS_RP5_L_N A19 UART_DSR_RP6_L_N 
B20 UART_DSR_RP5_L A20 UART_RX_RP6_L 
B21 UART_RX_RP5_L A21 UART_TX_RP6_L 
B22 UART_TX_RP5_L A22 UART_DTR_RP6_L_N 
B23 UART_DTR_RP5_L_N A23 UART_CTS_RP6_L 
B24 UART_CTS_RP5_L_N A24 UART_RI_RP6_L_N 



Open Compute Project  Open CloudServer OCS Chassis Management 
http://opencompute.org 5 
 
Pin Signal Pin Signal 
B25 UART_RI_RP5_L_N A25 GND 
B26 GND A26 FAN4_TACH 
B27 FAN1_TACH A27 FAN5_TACH 
B28 FAN2_TACH A28 FAN6_TACH 
B29 FAN3_TACH A29 GND 
B30 GND A30 FAN_PWM 
B31 T12_NODE1_EN A31 GND 
B32 T12_NODE2_EN A32 I2C_PSU3_SCL 
B33 T12_NODE3_EN A33 I2C_PSU3_SDA 
B34 T12_NODE4_EN A34 GND 
B35 GND A35 T11_NODE1_EN 
B36 UART_T12_NODE1XD A36 T11_NODE2_EN 
B37 UART_T12_NODE1_TXD A37 T11_NODE3_EN 
B38 UART_T12_NODE2_RXD A38 T11_NODE4_EN 
B39 UART_T12_NODE2_TXD A39 GND 
B40 GND A40 UART_T11_NODE1_RXD 
B41 UART_T12_NODE3_RXD A41 UART_T11_NODE1_TXD 
B42 UART_T12_NODE3_TXD A42 UART_T11_NODE2_RXD 
B43 UART_T12_NODE4_RXD A43 UART_T11_NODE2_TXD 
B44 UART_T12_NODE4_TXD A44 GND 
B45 GND A45 UART_T11_NODE3_RXD 
B46 T10_NODE1_EN A46 UART_T11_NODE3_TXD 
B47 T10_NODE2_EN A47 UART_T11_NODE4_RXD 
B48 T10_NODE3_EN A48 UART_T11_NODE4_TXD 
B49 T10_NODE4_EN A49 GND 
B50 GND A50 T9_NODE1_EN 
B51 UART_T10_NODE1_RXD A51 T9_NODE2_EN 
B52 UART_T10_NODE1_TXD A52 T9_NODE3_EN 
B53 UART_T10_NODE2_RXD A53 T9_NODE4_EN 
B54 UART_T10_NODE2_TXD A54 GND 
B55 GND A55 UART_T9_NODE1_RXD 



 
6 October 30, 2014 
 
Pin Signal Pin Signal 
B56 UART_T10_NODE3_RXD A56 UART_T9_NODE1_TXD 
B57 UART_T10_NODE3_TXD A57 UART_T9_NODE2_RXD 
B58 UART_T10_NODE4_RXD A58 UART_T9_NODE2_TXD 
B59 UART_T10_NODE4_TXD A59 GND 
B60 GND A60 UART_T9_NODE3_RXD 
B61 T8_NODE1_EN A61 UART_T9_NODE3_TXD 
B62 T8_NODE2_EN A62 UART_T9_NODE4_RXD 
B63 T8_NODE3_EN A63 UART_T9_NODE4_TXD 
B64 T8_NODE4_EN A64 GND 
B65 GND A65 T7_NODE1_EN 
B66 UART_T8_NODE1_RXD A66 T7_NODE2_EN 
B67 UART_T8_NODE1_TXD A67 T7_NODE3_EN 
B68 UART_T8_NODE2_RXD A68 T7_NODE4_EN 
B69 UART_T8_NODE2_TXD A69 GND 
B70 GND A70 UART_T7_NODE1_RXD 
B71 UART_T8_NODE3_RXD A71 UART_T7_NODE1_TXD 
B72 UART_T8_NODE3_TXD A72 UART_T7_NODE2_RXD 
B73 UART_T8_NODE4_RXD A73 UART_T7_NODE2_TXD 
B74 UART_T8_NODE4_TXD A74 GND 
B75 GND A75 UART_T7_NODE3_RXD 
B76 T6_NODE1_EN A76 UART_T7_NODE3_TXD 
B77 T6_NODE2_EN A77 UART_T7_NODE4_RXD 
B78 T6_NODE3_EN A78 UART_T7_NODE4_TXD 
B79 T6_NODE4_EN A79 GND 
B80 GND A80 PSU_ALERT_R_N 
B81 UART_T6_NODE1_RXD A81 T5_NODE1_EN 
B82 UART_T6_NODE1_TXD A82 T5_NODE2_EN 
Table 2 shows the pinout for the J35 PDB connector interface. 



Open Compute Project  Open CloudServer OCS Chassis Management 
http://opencompute.org 7 
 
Table 2: PDB connector interface (J35) 
Pin Signal Pin Signal 
B1 GND A1 GND 
B2 UART_T6_NODE2_RXD A2 T5_NODE3_EN 
B3 UART_T6_NODE2_TXD A3 T5_NODE4_EN 
B4 GND A4 GND 
B5 UART_T6_NODE3_RXD A5 UART_T5_NODE1_RXD 
B6 UART_T6_NODE3_TXD A6 UART_T5_NODE1_TXD 
B7 UART_T6_NODE4_RXD A7 GND 
B8 UART_T6_NODE4_TXD A8 UART_T5_NODE2_RXD 
B9 GND A9 UART_T5_NODE2_TXD 
B10 I2C_PSU2_SCL A10 UART_T5_NODE3_RXD 
B11 I2C_PSU2_SDA A11 UART_T5_NODE3_TXD 
B12 T4_NODE1_EN A12 UART_T5_NODE4_RXD 
B13 T4_NODE2_EN A13 UART_T5_NODE4_TXD 
B14 T4_NODE3_EN A14 GND 
B15 T4_NODE4_EN A15 T3_NODE1_EN 
B16 GND A16 T3_NODE2_EN 
B17 UART_T4_NODE1_RXD A17 T3_NODE3_EN 
B18 UART_T4_NODE1_TXD A18 T3_NODE4_EN 
B19 UART_T4_NODE2_RXD A19 GND 
B20 UART_T4_NODE2_TXD A20 UART_T3_NODE1_RXD 
B21 GND A21 UART_T3_NODE1_TXD 
B22 UART_T4_NODE3_RXD A22 UART_T3_NODE2_RXD 
B23 UART_T4_NODE3_TXD A23 UART_T3_NODE2_TXD 
B24 UART_T4_NODE4_RXD A24 GND 
B25 UART_T4_NODE4_TXD A25 UART_T3_NODE3_RXD 
B26 GND A26 UART_T3_NODE3_TXD 
B27 T2_NODE1_EN A27 UART_T3_NODE4_RXD 
B28 T2_NODE2_EN A28 UART_T3_NODE4_TXD 
B29 T2_NODE3_EN A29 GND 
B30 T2_NODE4_EN A30 T1_NODE1_EN 



 
8 October 30, 2014 
 
Pin Signal Pin Signal 
B31 GND A31 T1_NODE2_EN 
B32 UART_T2_NODE1_RXD A32 T1_NODE3_EN 
B33 UART_T2_NODE1_TXD A33 T1_NODE4_EN 
B34 UART_T2_NODE2_RXD A34 GND 
B35 UART_T2_NODE2_TXD A35 UART_T1_NODE2_RXD 
B36 GND A36 UART_T1_NODE2_TXD 
B37 UART_T2_NODE3_RXD A37 UART_T1_NODE3_RXD 
B38 UART_T2_NODE3_TXD A38 UART_T1_NODE3_TXD 
B39 UART_T2_NODE4_RXD A39 GND 
B40 UART_T2_NODE4_TXD A40 UART_T1_NODE4_RXD 
B41 GND A41 UART_T1_NODE4_TXD 
B42 I2C_PSU1_SCL A42 UART_T1_NODE1_RXD 
B43 I2C_PSU1_SDA A43 UART_T1_NODE1_TXD 
B44 GND A44 GND 
B45 PSU1_AC_OK A45 PSU1_DC_OK 
B46 PSU2_AC_OK A46 PSU2_DC_OK 
B47 PSU3_AC_OK A47 PSU3_DC_OK 
B48 PSU4_AC_OK A48 PSU4_DC_OK 
B49 PSU5_AC_OK A49 PSU5_DC_OK 
B50 PSU6_AC_OK A50 PSU6_DC_OK 
B51 GND A51 GND 
B52 UART_RTS_P5_L_N A52 UART_RTS_P6_L_N 
B53 UART_DSR_P5_L_N A53 UART_DSR_P6_L_N 
B54 UART_RX_P5_L A54 UART_RX_P6_L 
B55 UART_TX_P5_L A55 UART_TX_P6_L 
B56 UART_DTR_P5_L_N A56 UART_DTR_P6_L_N 
B57 UART_CTS_P5_L_N A57 UART_CTS_P6_L_N 
B58 UART_RI_P5_L_N A58 UART_RI_P6_L_N 
B59 GND A59 GND 
B60 UART_RTS_P1_L_N A60 UART_RTS_P2_L_N 



Open Compute Project  Open CloudServer OCS Chassis Management 
http://opencompute.org 9 
 
Pin Signal Pin Signal 
B61 UART_DSR_P1_L_N A61 UART_DSR_P2_L_N 
B62 UART_RX_P1_L A62 UART_RX_P2_L 
B63 UART_TX_P1_L A63 UART_TX_P2_L 
B64 UART_DTR_P1_L_N A64 UART_DTR_P2_L_N 
B65 UART_CTS_P1_L_N A65 UART_CTS_P2_L_N 
B66 GND A66 GND 
B67 NC A67 NC 
B68 NC A68 NC 
B69 NC A69 NC 
B70 NC A70 NC 
B71 GND A71 GND 
B72 LAN1_P3_P A72 LAN1_P1_P 
B73 LAN1_P3_N A73 LAN1_P1_N 
B74 GND A74 GND 
B75 LAN1_P4_P A75 LAN1_P2_P 
B76 LAN1_P4_N A76 LAN1_P2_N 
B77 GND A77 GND 
B78 CM_PWR_CTL_IN A78 P12V_PDB 
B79 P12V_PDB A79 P12V_PDB 
B80 P12V_PDB A80 P12V_PDB 
B81 MATE_R_N A81 P12V_PDB 
B82 P12V_PDB A82 P12V_PDB 
2.3 Blade Management 
The Chassis Manager is connected to each blade via two blade enable signals and two serial 
connections. Figure 4 shows the blade management connectivity from the Chassis Manager to the 
blades via the power distribution board and tray backplane. 
 



 
10 October 30, 2014 
 
CM
 PDB
C
O
M
4
UART4_TXD
UART4_RXD
M
U
X
UART_T[1:12]_
BLAD[1:4]_TX
UART_T[1:12]_
BLAD[1:4]_RD
CM CONN
CM CONN
UART_T[1:12]_
BLAD[1:4]_TX
UART_T[1:12]_
BLAD[1:4]_RD
PDB TRAY CONNECTOR
Motherboard
AIRMAX
BMC
NODE1_SIN
NODE1_SOUT
NODE2 for 
Debug Only
Blade1_EN
 In-Rush
Blade2_EN
+3.3V
Motherboard
AIRMAX
BMC
NODE1_SIN
NODE1_SOUT
NODE2 for 
Debug Only
Blade1_EN
 In-Rush
Blade2_EN
+3.3V
Tray Backplane
TRAY GOLD FINGER CONNECTOR
NODE1_TXD
NODE1_RXD
BLADE 1
NODE2_TXD
NODE2_RXD
NODE3_TXD
NODE3_RXD
NODE4_TXD
NODE4_RXD
NODE1_EN
NODE2_EN
BLADE 1
NODE3_EN
NODE4_EN
G
P
I
O
T[1:12]_BLAD[1:4]_TX
T[1:12]_
BLAD[1:4]_EN
 
Figure 4: Blade management connectivity 
2.4 Power Control 
The Chassis Manager provides controls for power of the blades and remote devices.  At web-scale, 
definitive control over power is necessary to provide a clean reset in the event of locked-up or hung 
circuits. 
2.4.1 Blade Power Control 
The blade enable signals indicate on/off to the in-rush controller on the blade to emulate a full 
power off. 
The blade enable signals are implemented via General Purpose I/O (GPIO) registers.  The default is 
to float high via pull-ups on the blade, so that when the Chassis Manager is removed or when the 
power is cycled for service, blade operation is not disrupted. 
The signals are grouped to make it possible for all blades on a single tray to be powered on/off 
coincidently, and to let blades on different trays be powered on/off either coincidently or through 
timed power control. 
Timed power control can be used to control servers and JBODs (for example, to prevent incorrect 
errors from being reported when using a head server node and JBOD blades). The following steps 
can be used: 
1. Power off the head (server) node, and allow a short delay. 



Open Compute Project  Open CloudServer OCS Chassis Management 
http://opencompute.org 11 
 
2. Power off the JBOD blade, and allow a five second delay. 
3. Power on the JBOD blade, and allow a short delay.  
4. Power on the head (server) node. 
Timed delays can be easily adjusted to match the needs of the hardware and storage though the 
Chassis Manager. 
2.4.2 Remote Power Control 
It is important to have full power control over remote devices such as network switches or other 
Chassis Managers. 
The remote power controls are 12V on/off signals. The default is 0V (ON). Off is 12V, so that if a 
Chassis Manager is removed or if the power is cycled, remote device operation is not disrupted.   
The individual signals are: 
 ON/OFF input  
Accepts the 12V signal from a remote Chassis Manager for power control 
 Three ON/OFF outputs  
Allows control of remote devices 
2.5 Communication Ports 
Table 3 lists the definition and translation of the serial COM port signals of the RJ-45 connector for 
ports 1 and 2 (see Figure 3).  
These definitions match the functionality of switch consoles that use RJ-45, but can be used to 
select cables that convert from DB-9 or DB-25 connections. The system swaps received 
data/transmitted data (RxD/TxD), clear to send/request to send (CTS/RTS), and data terminal 
ready/data set ready (DTR/DSR) signals so a straight Ethernet cable can be used. 
Table 3: Serial RJ-45 cable definition for ports 1 and 2 
 PDB connection  
ports 1 and 2 Typical switch management port 
Signal on CM board RJ-45 connector pin RJ-45 connector pin Switch console port  
RTS 1 1 CTS 
DSR 2 2 DTR 
RxD 3 3 TxD 
GND 4 4 GND 
GND 5 5 GND 



 
12 October 30, 2014 
 
 PDB connection  
ports 1 and 2 Typical switch management port 
Signal on CM board RJ-45 connector pin RJ-45 connector pin Switch console port  
TxD 6 6 RxD 
DTR 7 7 DSR 
CTS 8 8 RTS 
Table 4 lists the definition and translation of the serial COM port signals of the RJ-45 connector for 
serial COM ports 5 and 6 (see Figure 3). COM port 3 and 4 are internal to the Chassis Manager 
board. 
Table 4: Serial RJ-45 cable definition for ports 5 and 6 
 PDB connection  
ports 5 and 6 Typical switch management port 
Signal on CM board RJ-45 connector pin RJ-45 connector pin Switch console port  
RTS 1 1 CTS 
DSR 2 2 DTR 
RxD 3 3 TxD 
RI 4 4 GND 
GND 5 5 GND 
TxD 6 6 RxD 
DTR 7 7 DSR 
CTS 8 8 RTS 
2.6 Mechanical Specifications 
Figure 5 shows the mechanical control outline for the Chassis Manager.  Also shown (circled in red) 
are the edge fingers that provide connectivity to the power distribution board. 



Open Compute Project  Open CloudServer OCS Chassis Management 
http://opencompute.org 13 
 
 
Figure 5: Chassis manager dimensions and edge finger locations 
2.7 Chassis LEDs 
Each chassis has two light-emitting diodes (LEDs) on the Chassis Manager: a health status LED that 
is green and an attention LED that is red. Both LEDs are driven by a single GPIO bit off the blade’s 
management i2c tree. 
2.7.1 Chassis Health Status LED 
The chassis health status LED indicates whether the Chassis Manager has booted. Note that if the 
12V power is off, the LEDs on the power supplies are also off. Table 5 describes the operation of the 
chassis health status LED. 
Table 5: Chassis health status LED description 
LED Status Condition 
Off 
 Backplane 12V power is off if power supply LEDs are off 
 Backplane 12V power is on, but Chassis Manager never booted if 
power supply LEDs are on 
Solid green on Backplane 12V power is on and Chassis Manager has booted 


 
14 October 30, 2014 
 
2.7.2 Chassis Attention LED 
The chassis attention LED is visible from the rear of the chassis without opening the fan tray. This 
LED directs service technicians to the correct chassis during repair. When possible, blade 
diagnostics are used to direct repairs; alternately, the scale-out management software can be used. 
In both cases, logs of the repair work are available.  
The chassis attention LED indicates the following conditions: 
 Operator directed 
An operator can manually set the chassis attention LED (for example, identification of chassis 
cables) 
 Power supply failure 
Chassis Manager has detected a power supply failure  
 Fan failure 
Chassis Manager has detected a fan failure 
Note that the chassis attention LED must be turned off after service is complete.  
Table 6 describes the operation of the chassis attention LED. 
Table 6: Chassis Attention LED description 
LED Status Condition 
Off  No attention indicated 
Solid red  Operator directed 
 Power supply or fan failure 
3 Systems Management Operations 
The following sections describe the system management operations for the rack infrastructure, and 
for the in-band and out-of-band (OOB) management paths. 
Systems management is designed to present a consistent, optimized interface. The Chassis 
Manager provides the front end through an applications interface (RESTful web API) for automated 
management and a CLI for manual management. The Chassis Manager manages all devices within 
the rack and communicates directly with the blade management system through a serial 
multiplexor. 
There are two possible paths for systems management: in-band and out-of-band.  



Open Compute Project  Open CloudServer OCS Chassis Management 
http://opencompute.org 15 
 
 The in-band management path is through the primary network interface card (NIC) while the 
operating system is running.  
  The out-of-band path is through the Chassis Manager.  
In-band is the preferred path for systems management whenever possible. 
3.1 Rack and Chassis Manager Commands 
The Chassis Manager is responsible for managing the blades and the infrastructure within the rack. 
It monitors the health of the power supplies and the fans and sets the fan speeds. Because the 
Chassis Manager is the gateway into the system, it also gathers all information necessary to 
perform wiring checks by identifying the nodes in each slot and identifying their media access 
control (MAC) addresses, the switches, and the cable MAC addresses. 
Table 7 lists the functionality of the commands that apply to the rack infrastructure. 
Table 7: Rack infrastructure command functionality 
Requirement Details 
Switch power control 
(complete ON/OFF) 
Cycle the power to the switch (two 12V signals are driven by the 
Chassis Manager) 
Rack identification 
Provides an inventory of rack hardware: 
 Chassis manager information 
 Chassis numbers installed (part number, serial number) 
 Power supply unit and fan status 
Blade identification 
For every blade slot in every chassis: 
 Present 
 Type 
 Location and network connections 
 Network MAC addresses 
 Asset information (such as globally unique identifier [GUID]), 
device type, and versions) 
 Fan cubic feet per minute (CFM) requirement for each blade 
Network identification 
For every network switch in the rack managed by the CM: 
 Status 
 GUID 
 Status and MAC addresses connected to each port 



 
16 October 30, 2014 
 
Requirement Details 
Power supply unit (PSU), fan 
status 
 PSU DC-OK 
 AC-OK 
 Fan tachometer 
 Fan setting 
Fan speed control  Required fan speed 
Chassis power consumption For use with advanced power capping, integration with rack-level 
uninterrupted power supply (UPS), high temperature operation 
Manageability firmware update  To update microcontrollers within the chassis through the CM   
 To update PSU and fan control firmware, if applicable 
User management 
 Security privilege levels for users connected to the CM (for 
example, not all users logged into the CM will be able control fan 
speed or powering blades ON/OFF)   
 Security privilege mechanisms are still TBD 
3.2 In-Band Management Commands 
The primary method for managing servers is in-band through the operating system.  The system 
can use a unified extensible firmware interface (UEFI) that allows more functionality through the 
primary NIC, though this is not considered to be in-band and is not mandatory for interoperability. 
UEFI can initialize the NIC very early in the boot sequence, and can implement serial-over-local area 
network (SOL) to complement Windows 8 SOL support for system debug. 
The path through the operating system uses the native Windows intelligent platform management 
interface (IPMI) driver and native IPMI Windows management instrumentation (WMI) provider. The 
baseboard management controller (BMC) firmware must be compatible with the native Windows 
IPMI keyboard controller style (KCS) interface driver.  
A number of functions are implemented with a utility that is traditionally run under the operating 
system; these utilities could be run under UEFI (method to be determined).   
Table 8 lists command functionality that is supported by the in-band path. Note that it is assumed 
that a hardware monitoring device (HMD) will be present on the motherboard to provide 
management functionality. 



Open Compute Project  Open CloudServer OCS Chassis Management 
http://opencompute.org 17 
 
Table 8: Command functionality supported by in-band path 
Function Method Function details 
Identification WMI 
 HMD ID/version information 
 System GUID 
 HMD MAC address (only if sideband LAN access is 
provided) 
 Server MAC address 
 Asset tag 
Chassis power WMI 
 Power ON 
 Power OFF 
 Warm reset 
Console 
Windows 8 and 
UEFI SOL, Chassis 
Manager 
 Serial console 
Basic input/output 
system (BIOS) 
firmware update 
Utility  Motherboard flash 
Manageability 
firmware update Utility  Motherboard flash 
Host configuration 
BIOS settings Utility 
 Boot order 
 Power policy 
 Real-time clock 
Event logging WMI 
 Get log in IPMI SEL format 
 Clear log 
 Logs for AP/FC remote management agent (RMA) 
diagnosis and ticketing 
Temperature 
monitoring WMI 
 Inlet  
 Exhaust 
 CPU temperature 
Power management WMI 
 Set power limit 
 Get power limit 
 Get power reading 
Performance/power 
state WMI  Power capping 



 
18 October 30, 2014 
 
Function Method Function details 
Failure and wear 
indicators WMI 
Includes HDD and SSD self-monitoring, analysis and 
reporting technology (SMART) data, memory error logs, 
and more 
3.3 Out-of-Band Management Commands 
A few server management functions use the out-of-band management path through the serial link 
that is connected to the Intel® Manageabilty Engine (ME) or HMD.   
Table 9 lists the blade management command functionality that is supported by out-of-band path. 
Table 9: Command functionality supported by out-of-band path 
Function Function details Descriptions 
Identification 
 HMD MAC address 
 Server MAC address 
 Asset tag 
 MAC addresses used for discovery and wiring 
checks 
 Asset tag is used for tax compliance audits 
Blade node 
power 
 Hard power ON 
 Hard power OFF 
 Drives the Blade_EN to the in-rush controller to 
perform full power ON/OFF  
 OFF also turns off power to the Intel ME/HMD 
Blade node 
power 
 Soft power ON 
 Soft power OFF 
 Warm reset 
 Under direction of the Intel ME ME or HMD 
Event logging 
 Power status 
(ON/OFF/sleep) 
 Health status 
(healthy/error) 
 Fan/CFM request 
 Provides at-a-glance status of server 
 Fan/CFM information is polled every 10 seconds 
 



Open Compute Project  Open CloudServer OCS Chassis Management 
http://opencompute.org 19 
 
4 Chassis Manager Services 
Figure 6 shows the services that the Chassis Manager provides. 
 
Figure 6: Chassis manager services 
Table 10 lists the Chassis Manager services, and the sections that follow provide additional 
description. 
Table 10: Chassis manager services 
Chassis manager 
service Description 
Fan service 
Controls the fan speed of all the fans housed in the chassis to keep the servers 
cool and operational 
Checks the status of every fan and alerts when a fan speed becomes unrealistic 
PSU service 
Reads the status of every power supply unit (PSU) in the chassis and sends an 
alert if a PSU goes down or malfunctions 
Reports power reading for every PSU  
Power control service Provides the service to power ON/OFF every blade in the chassis 


 
20 October 30, 2014 
 
Chassis manager 
service Description 
Blade management 
service 
Provides the following blade management services:  
 Chassis power management (ON/OFF/reset) 
 Field replaceable unit (FRU) management 
 Sensor management 
 Serial console redirection 
 Blade ID (through LED) 
Top-of-rack (TOR) 
service 
Provides a serial connection to the TOR and acts as a gateway to all serial 
communication to the TOR 
Security Allows for creating users, deleting users, and updating user properties such as 
passwords 
Chassis manager 
control services 
Exposes commands to manage the Chassis Manager itself (for example, NIC 
settings of the NIC ports) 
4.1 Fan Control Protocol 
This section describes the fan control protocol, and provides an example for calculating the pulse-
width modulation (PWM) sensor reading. 
Table 11 lists the input and output for the fan control software. 
Table 11: Input and output for fan control software 
Description 
Input  PWM sensor reading from each blade 
 Time period for sampling 
Output  Fan PWM for setting fan speed for the entire chassis 
4.1.1 Determining Fan Speed 
The Chassis Manager uses the following steps to determine the fan speed: 
1. Get PWM sensor values from the blade (see the example in the section that follows). 
a. The IPMI Get Sensor Reading command is used to get the PWM sensor values from the 
blade. Note that the PWM sensor ID is 1. (This sensor should also be the first sensor 
enumerated in the IPMI sensor data record [SDR].) 
b. This sensor reading is sampled for each blade periodically; this time period is 
determined by the configuration parameter when the Chassis Manager starts (currently 



Open Compute Project  Open CloudServer OCS Chassis Management 
http://opencompute.org 21 
 
this configuration parameter is set by default to 10 seconds, which means each blade is 
polled exactly every 10 seconds). 
2. Set PWM value as fan speed. 
a. The Chassis Manager identifies the maximum value from all its constituent blade PWM 
values, and then sets the fan PWM to that value. Note that currently all the fans are set 
to the same speed. 
3. Correct for altitude. 
a. The fan speed is corrected for altitude using linear interpolation (see the hardware 
specification for more detail). 
b. Current altitude is obtained from the configuration file; if no altitude is present, this 
correction is not performed. 
4. Correct for one fan failure if necessary. 
a. If there is one fan failure, the PWM calculated from step 2 is scaled with the multiplier 
(maximum number of fans)/(maximum number of fans - 1). 
b. This linear scaling of fan PWM requested (within maximum limit of 100) is sufficient to 
handle one fan failure. 
c. The Chassis Manager also logs an error and sets the attention LED. 
5. Correct for more than one fan failure if necessary. 
a. If there is more than one fan failure, the Chassis Manager sets the fan speed to 
maximum PWM (100). It also logs an error and sets the attention LED. 
4.1.2 Sample PWM Calculation 
Following is an example of calculating the blade PWM sensor ID. This value should be exposed as a 
logical IPMI sensor with a lower limit of 20 and an upper limit of 100. 
The algorithm is based on a feedback control loop that checks every sensor on the list (specified as 
priority level 1 to N) against a target specified by the component manufacturer for maximum 
reliability. The algorithm then computes the relative PWM increase or decrease required and sends 
this value to the blade. 
Table 12 lists the input and output for the main algorithm. 
Table 12: Input and output for fan control software 
Description 
Input  Sensor priority 
 Sensor target 
Output  PWM value 
 Increase/decrease request 



 
22 October 30, 2014 
 
Following is the pseudocode for the process: 
1. Create a sensor reading table T[1..N]. See Table 13 for the example. 
2. For each sensor (with priority 1..N), run the following statements: 
  If (sensor.currentValue != sensor.target) 
   Difference = sensor.currentvalue - sensor.target 
   PWMstep = ExponentialFunction(Step, Difference) 
   Input PWMstep into table location T[sensor.priority] 
  EndIf 
EndDo 
3. Find the maximum value from table T[1..N], and supply the absolute PWM value and a code 
that specifies whether to decrease or increase the PWM (based on negative or positive 
difference value) as part of the response packet.  
The function ExponentialFunction(step, difference) enables the decrease or 
increase in PWM based on distance from the target value. If the current value is very close to target 
value, the exponential function will return smaller step; if the current value is very far away from 
target value, the exponential function will return larger step. This keeps decay slow and controls 
linear swings between extremes. The exponential function is tuned specifically for each sensor. 
If none of the sensor values are valid, then the appropriate PWM should be determined by the 
blade vendor (this could be maximum or minimum PWM based on thermal profiles). Note that if 
the current temperature is higher than the high temperature, the PWM value is reset to Max PWM. 
The inlet temperature sensor is treated differently from the other sensors. It is used to define a 
base fan speed relative to the intake temperature to provide cooling for all components that are 
not directly monitored, and should ramp fan speeds up with inlet temperature increases as 
appropriate.  
Table 13 shows an example of a sensor reading table. 
Table 13: Example sensor readings 
Sensor Target High critical Priority 
Inlet 30-55 38 1 
CPU 2 (downstream) 74 90 2 
CPU 1 74 90 3 
HDD 3 (downstream) 40 60 4 
HDD 4 (downstream) 40 60 5 
HDD 1 40 60 6 
HDD 2 40 60 7 



Open Compute Project  Open CloudServer OCS Chassis Management 
http://opencompute.org 23 
 
Sensor Target High critical Priority 
PCH 90 95 8 
DIMM 10 (downstream) 80 90 9 
DIMM 11 (downstream) 80 90 10 
DIMM 12 (downstream) 80 90 11 
DIMM 13 (downstream) 80 90 12 
DIMM 14 (downstream) 80 90 13 
DIMM 15 (downstream) 80 90 14 
DIMM 16 (downstream) 80 90 15 
DIMM 9 (downstream) 80 90 16 
DIMM 1 80 90 17 
DIMM 2 80 90 18 
DIMM 3 80 90 19 
DIMM 4 80 90 20 
DIMM 5 80 90 21 
DIMM 6 80 90 22 
DIMM 7 80 90 23 
DIMM 8 80 90 24 
The Chassis Manager polls all these PWM values from each individual blade, computes the 
maximum, and sets the fan speed accordingly. 
4.2 Blade State Management 
The Chassis Manager needs to keep track of the state of all its blades to discover new blades and to 
optimize the code behavior. For example, if only one out of N blades is powered on, the Chassis 
Manager should not try to get sensor readings from the rest of the blades because the sensor-read 
command is time consuming.  
Figure 7 lists states and transitions for managing the blades. The Chassis Manager maintains these 
values for blades it controls.  



 
24 October 30, 2014 
 
 
Figure 7: Blade state management 
Note that there are only two user-facing commands that can change the state of the blade: power 
ON and power OFF (Blade Enable ON and Blade Enable OFF) commands. IPMI commands are not 
part of the blade state because they are served in operational states (probation and healthy states. 
See Table 14 for more detail.  
Table 14: Blade states 
Blade state Description 
Initialize (I) 
Captures the blade initialization steps when Chassis Manager starts or when a new 
blade is inserted.  
Creates client objects and of obtains IPMI session authentication, the GUID of the 
blade, and the SDR, which supplies the low and high threshold values for the fan 
algorithm.  
Checks the power enable status of the blade and moves the blade to:  
 Blade Enable Off (PEoff) if the blade is set to OFF 
 Probation (P) if initialization succeeds 
 Fail (F) if initialization does not succeed 
Blade Enable 
OFF (PEoff) 
Captures the state where the blade enable is off.  
All commands fail in this state except power ON.  
Periodically checks the power enable state to see if it is still in Blade Enable OFF. 


Open Compute Project  Open CloudServer OCS Chassis Management 
http://opencompute.org 25 
 
Blade state Description 
Probation (P) 
Transitory state that logically separates the operational states, making it possible to 
use a light-weight “get GUID” command as the heartbeat in the fail state.  
Prevents the fail count from being reset (catching “Get GUID” success and read 
sensor failure event loops).  
Chassis manager tries to serve one sensor read request in this state; if that succeeds, 
it moves to the healthy state. 
Healthy (H) 
Most blades should be in this state; transition to fail only when all temperature 
sensor reads fail 
Keep serving IPMI requests 
Fail (F) 
Non-operational, cannot serve any requests 
Increment fail count every time state is encountered from outside or through self-
loops 
At each iteration, try to get GUID with light-weight heartbeat: 
 If heartbeat succeeds and GUID has changed, re-initialize client 
 If heartbeat succeeds and GUID has not changed, blade moves to probation and 
back to healthy 
Note that if the fail count goes beyond a maximum (fail count > max), tries an 
initialization action for IPMI; this prevents infinite loops and discovers newly inserted 
blades 
4.3 Chassis Manager Component Failure Scenarios 
The Chassis Manager handles only fan failures: 
 Single fan failure:  
The Chassis Manager logs an error, sets fan speed to 6/5, and turns on the attention LED. 
 Two or more fan failures:  
The Chassis Manager logs an error, sets fan speed to high, and turns on the attention LED. 
For all other failures, the Chassis Manager only logs an error and turns on the attention LED; by 
design, the Chassis Manager takes no pre-emptive action (for example, no action other than logging 
the error and turning on the attention LED is taken for PSU or blade-specific failures).  



 
26 October 30, 2014 
 
5 Chassis Manager/Blade APIs 
The Chassis Manager/blade protocol is a small subset of the intelligent platform management 
interface (IPMI2.0) protocol. IPMI2.0 is therefore not required for the blade and Chassis Manager to 
communicate; only message format compatibility with IPMI2.0 is required.   
The Chassis Manager communicates with the target blade BMC firmware using IPMI basic mode 
over the IPMI Serial/Modem Interface (Reference: IPMI 2.0—14.4 Basic Mode). 
Note: For the purpose of completeness, this document contains abstracts and references to the 
IPMI 2.0 specification http://www.intel.com/content/www/us/en/servers/ipmi/ipmi-home.html 
and to the DCMI 1.5 specification http://www.intel.com/content/www/us/en/data-
center/dcmi/data-center-manageability-interface.html. References to these documents are not 
subject to the Microsoft OWF CLA 1.0 commitment for this specification.  
Table 15 lists the IPMI commands that are required or optional for compute blades and storage 
blades. (Note that “M” is mandatory and “O” is optional.)  
Note: Storage blade command requirements differ from compute blade commands.  
Table 15: Required IPMI fields for blades 
Command name Reference Type Fn Cmd Compute 
blade 
JBOD 
blade 
Get Device ID  20.1 App 06h 01h M M 
Get System GUID  22.14 App 06h 37h M M 
Get Channel 
Authentication 
Capabilities 
22.13 App 06h 38h M M 
Get Session Challenge  22.16 App 06h 39h M N/A 
Activate Session  22.17 App 06h 3Ah M N/A 
Set Session Privilege 
Level  22.18 App 06h 3Bh M N/A 
Close Session  22.19 App 06h 3Ch M N/A 
Get Message 22.6 App 06h 33h M N/A 
Send Message 22.7 App 06h 34h M N/A 
Get Chassis Status  28.2 Chassis 00h 01h M M 
Chassis Control  28.3 Chassis 00h 02h M N/A 
Chassis Identify  28.5 Chassis 00h 04h M N/A 
Set Power Restore 
Policy  28.8 Chassis 00h 06h M N/A 



Open Compute Project  Open CloudServer OCS Chassis Management 
http://opencompute.org 27 
 
Command name Reference Type Fn Cmd Compute 
blade 
JBOD 
blade 
Set Power Cycle 
Interval  28.9 Chassis 00h 0Bh M N/A 
Set System Boot 
Options  28.12 Chassis 00h 08h M N/A 
Get System Boot 
Options  28.13 Chassis 00h 09h M N/A 
Get Sensor Reading 
Factors  35.5 Sensor 04h 23h M N/A 
Get Sensor Reading 35.14 Sensor 04h 2Dh M N/A 
Get Sensor Type  35.16 Sensor 04h 2Fh M N/A 
Read FRU Data  34.2 Storage 0Ah 11h M M 
Write FRU Data  34.3 Storage 0Ah 12h M M 
Reserve SDR 
Repository  33.11 Storage 0Ah 22h M N/A 
Get SDR  33.12 Storage 0Ah 23h M N/A 
Reserve SEL  31.4 Storage 0Ah 42h M N/A 
Get SEL Entry  31.5 Storage 0Ah 43h M N/A 
Add SEL Entry  31.6 Storage 0Ah 44h M N/A 
Clear SEL  31.9 Storage 0Ah 47h M N/A 
Set Serial/Modem 
Mux  25.3 Transport 0Ch 12h M N/A 
Get Power Reading N/A DCMI 2Ch 02h M N/A 
Get Power Limit N/A DCMI 2Ch 03h M N/A 
Set Power Limit N/A DCMI 2Ch 04h M N/A 
Activate Power Limit N/A DCMI 2Ch 05h M N/A 
Get Processor Info N/A OEM 30h 1Bh M N/A 
Get Memory Info N/A OEM 30h 1Dh M N/A 
Get PCIe Info N/A OEM 30h 44h M N/A 
Get Nic Info N/A OEM 30h 19h M N/A 
BMC Debug N/A OEM 30h F9h M N/A 
Get BIOS Code N/A OEM 32h 73h M N/A 
Get Disk Status N/A OEM 
Group 2Eh C4h N/A M 
Get Disk Info N/A OEM 
Group 2Eh C5h N/A M 
M = Mandatory, N/A = Not applicable to blade typ 



 
28 October 30, 2014 
 
5.1 Blade Implementation Requirements 
The following sections describe the blade implementation requirements. 
Only a small subset of commands of IPMI2.0 is required to work with the Chassis Manager. If a 
blade implements IPMI2.0 and conforms to the requirements described in the sections that follow, 
it is safe to assume that the blade is compatible with the Chassis Manager.  
5.1.1 IPMI Interfaces 
 Keyboard Controller Style (KCS) for SMS or BT Interface 
 Serial Interface 
5.1.2 IPMI Bus Support 
 Intelligent Platform Management Bus (IPMB) 
 System Bus (system Interface) 
 SMBus (I2C) 
 Serial - IPMI Basic Mode 
5.1.3 Intel® Node Manager 
Blades containing Intel processors with the Intel ME® Manageability Engine should have Intel® 
Node Manager enabled in the configuration.  The BMC IPMB Channel Number should be 6 to align 
with the reference code default. This deviates from the IPMI 2.0 specification whereby the Primary 
IPMB Channel Number is 0.  
5.1.4 BMC Debug Port 
The Blade Hardware specification defines a dedicated BMC UART for the purpose of BMC debug. 
This port should allow IPMI over serial commands be sent directly to the BMC and should support a 
BMC debug mode whereby the BMC diagnostic can directly be interrogated. The default serial port 
baud rate should be set to 115.2 kbps.  
5.1.5 BMC Bypass Jumper 
The BMC can be enabled/disabled using the baseboard jumper (see the Blade Hardware 
specification for jumper numbering and references). This jumper will suspend BMC operation 
during the boot process, disabling watch dog interrupts and BMC activity. The jumper is for debug 
only, when the BMC prevents system BIOS diagnostic or the BMC is suspected of causing a boot 
failure. 



Open Compute Project  Open CloudServer OCS Chassis Management 
http://opencompute.org 29 
 
5.1.6 BMC Diagnostic Login 
The BMC diagnostic console login user name and password should be set as follows:  
 Username = sysadmin  
 Password = superuser 
5.1.7 IPMI Serial Session Login 
The IPMI session authentication username and password should be set as follows: 
 Username = admin 
 Password = admin 
5.1.8 Serial Port Timeout 
The serial line has a receiving transmission timeout of 100 milliseconds (ms). The BMC must 
therefore respond to all serial IPMI requests within 100ms. When it receives a response from the 
baseboard management controller (BMC), the Chassis Manager might immediately send another 
request. It is therefore possible that the BMC will receive multiple requests within a 100ms 
timeframe, depending on its response time.   
5.1.9 Session Timeout 
IPMI basic mode over a serial interface allows only one IPMI session. The IPMI session termination 
and timeout must be able to be configured with the Set Serial/Modem Configuration command. 
The timeout period is set in 30 second increments. The termination command must allow inactivity 
timeout termination. The default timeout preconfigured in the IPMI firmware should be 180 
seconds. 
5.1.10 BMC Serial Port Baud Rate 
The blade IPMI basic mode default serial port baud rate should be set to 115.2 kbps. The IPMI serial 
port baud rate must be able to be configured with the Set Serial/Modem Configuration command.  
115.2Kbps should be the default set in the System BIOS. 
5.1.11 Sensor Data Record  
The pulse-width modulation (PWM) sensor is the first sensor data record; however, if an alternative 
temperature sensor is preferred, this sensor can be the first sensor stored in the sensor data record 
(SDR). When enumerating the SDR, the first record accessed (0000) must always be the PWM or the 
alternative temperature sensor, depending on the PWM implementation. 



 
30 October 30, 2014 
 
5.1.12 System Event Log 
The System Event Log (SEL) should implement circular logging.  The maximum number of records in 
the circular log should be 226 records or roughly 4KB in memory.  When the SEL is full, the log 
should overwrite the oldest record with the newest record. 
5.1.13 Event Throttling 
Certain system events that are generated in quick succession may need to be throttled so they 
don’t overwhelm the BMC. 
For example, during temperature excursions, PROCHOT events may occur in quick succession 
causing the Intel ME to send  many “Add SEL Entry commands via the IPMB to the BMC for CPU 
Thermal Status.  The system should be configured to perform the following to prevent the BMC 
from becoming overwhelmed: 
1. Register the CPUx_PROCHOT interrupt configuration to the falling edge trigger. 
a. When interrupt occurs, the BMC will proceed with the following steps: 
1. Unregister interrupt configuration for CPUx_PROCHOT. 
2. Log “CPUx_PROCHOT asserted” SEL for this event. 
3. Wait for 1 minute. 
2.  After 1 minute, the BMC will proceed with the following steps: 
a. Register interrupt configuration for CPUx_PROCHOT again. 
b.  If there are still interrupts occurring, unregister interrupt configuration again, but do 
not log SEL. Proceed with step a) again after 1 minute. 
c. If there is no new interrupt occur for 10 seconds, check the level of CPUx_PROCHOT.  If 
CPUx_PROCHOT is HIGH, BMC should log “CPUx_PROCHOT deasserted” SEL. 
The PROCHOT signal from each CPU will be handled independently. For example, if CPU0_PROCHOT 
asserts, the above procedure should be executed for CPU0_PROCHOT only. If CPU1_PROCHOT is 
asserted while CPU0_PROCHOT is unregistered, the BMC should log “CPU1_PROCHOT asserted” 
SEL. 
5.1.14 Keyboard Controller Style Interface 
The BMC on compute blades should support the Native Microsoft Windows Server 2012 PMI driver 
for IPMI communication within the host operating system to the BMC. 
5.1.15 Serial Port Sharing 
The Chassis Manager to blade BMC communication will use the same serial connection to send 
IPMI commands and execute Serial Console Redirection to the blade.  To fulfill this requirement the 
BMC should support Serial Port Sharing as described in the IPMI 2.0 specification (see Figure 8).   



Open Compute Project  Open CloudServer OCS Chassis Management 
http://opencompute.org 31 
 
In the default condition, the mux setting will be MUX_BMC, which is standby to service IPMI 
command payloads.  When the Chassis Manager requires console redirection from the blade, the 
MUX setting will change to MUX_SYS.  While MUX_SYS is activated, the Chassis Manager can 
change back to MUX_BMC using the methods listed in Figure 8.  
Figure 8: Serial port sharing mux diagram 
 
5.1.16 Firmware Decompression 
The BMC firmware must deterministically be fully decompressed (loaded) and ready to service IPMI 
request messages within 24 seconds.  Any unused modules from the base firmware that cause 
decompression delays should be removed. 
5.1.17 Inlet Sensor 
The blade inlet sensor should be always be sensor number B0h in the Sensor Data Repository (SDR). 
If the inlet sensor requires an offset caused by hard disk preheat, the offset will be applied by the 
Chassis Manager after reading the sensor value. It is the responsibility of the blade manufacturer to 
supply Microsoft with the offset that needs to be applied. The Chassis Manager will identify the 
blade using the Get Device Id IPMI command.  
The [8:10] Manufacturer Id and [11:12] Production Id are used to identify the 
blade manufacturer and product. The product ID for this specification should be 1030. The 
manufacturer Id should comply with the IPMI specification and IANA “Private Enterprise” ID. If the 
inlet temperature sensor requires an offset, the Get Device Id command bytes [8:10] 
Manufacturer Id should not be 000000h = unspecified or 0FFFFFh = reserved.  


 
32 October 30, 2014 
 
5.2 Request and Response Packet Formats 
Every request message from the Chassis Manager software has the format shown in Figure 9. 
rsAddress Function checksum rqAddress Seq cmd payload checksum
1 byte 1 byte 1 byte 1 byte 1 byte 1 byte n byte 1 byte
1 2 3 4 5 6 N N+1
 
Figure 9: Request packet format 
Every response from the Chassis Manager software to a request has the format shown in Figure 10. 
rqAddress Function checksum rsAddress Seq cmd completion
code checksumpayload
1 byte 1 byte 1 byte 1 byte 1 byte 1 byte 1 byte n byte 1 byte
1 2 3 4 5 6 7 N N+1
 
Figure 10: Response packet format 
Table 16 provides details of the request and response packets. 
Table 16: Details for Request and Response Packets 
Number Packet Description 
1 rqAddress 
Requester address, 1 byte 
Least-significant (LS) bit is 0 for slave addresses and 1 for software IDs  
Upper 7-bits hold slave address or software ID, respectively  
Byte is 20h when the BMC is the requester 
2 Function 
Function code   
Response function = request function +1 [debug identification] 
3 Checksum 
2's complement checksum of preceding bytes in the connection header  
8-bit checksum algorithm: initialize checksum to 0   
For each byte, checksum = (checksum + byte) modulo 256, then checksum = - 
checksum   
When the checksum and the bytes are added together, modulo 256, the 
result should be 0 



Open Compute Project  Open CloudServer OCS Chassis Management 
http://opencompute.org 33 
 
Number Packet Description 
4 rsAddress 
Responder slave address, 1 byte  
LS bit is 0 for slave addresses and 1 for software IDs  
Upper 7-bits hold slave address or software ID, respectively  
This byte is 20h when the BMC is the responder; the rqAddress will be the 
software ID from the corresponding request packet 
5 Seq Sequence number, generated by the requester 
6 Cmd Command byte 
7 Completion 
code 
Completion code returned in the response to indicated success/failure status 
of the request 
N Payload As required by the particular request or response for the command 
N+1 Checksum 
2's complement of bytes between the previous checksum   
8-bit checksum algorithm: Initialize checksum to 0   
For each byte, checksum = (checksum + byte) modulo 256, then checksum = - 
checksum   
When the checksum and the bytes are added together, modulo 256, the 
result should be 0 
5.3 Packet Framing 
Special characters are used to delimit the start and end of a command packet.  
Table 17 lists the packet framing characters. Note that the framing and data escape characters are 
applied after the message fields have been formatted.   
Table 17: Special characters used for packet framing 
Description Value 
Start character A0h 
Stop character A5h 
Packet handshake  A6h 
Data escape character AAh 
Message framing is similar to inter-integrated circuit (I2C) conditional framing, but replaced with 
start and stop characters and with the addition of a data byte escape character to ensure that the 
framing characters are not encountered within the body of the packet. The packet handshake 



 
34 October 30, 2014 
 
character is used for implementing a level of software flow control with the remote application that 
is accessing the BMC. 
The start, stop, and escape characters are not allowed within the body of the message to make sure 
that the beginning and end of a message is unambiguously delimited. If a byte matching one of the 
special characters is encountered in the data to be transmitted, it is encoded into a corresponding 
two-character sequence for transmission. Table 18 summarizes these encoding sequences. 
Table 18: Encoding sequences for special characters 
The first character of the sequence is always the escape character. Only the special characters plus 
the ASCII escape <ESC> character, 1Bh, are escaped. (Note that the ASCII escape <ESC> character, 
1Bh, is escaped to let the BMC snoop for certain escape sequences in the data stream, such as the 
<ESC>( and <ESC>Q patterns.) All other byte values in the message are transmitted without 
escaping.  
When the packet is received, the process is reversed. If the two-byte escape sequence is detected 
in the packet, it is converted to the corresponding data-byte value. Note that the BMC will reject 
any messages that have illegal character combinations or that exceed message buffer length limits. 
The BMC may not send an error response for these conditions. 
The handshake character is used to signal that the BMC has freed space in its input buffers for a 
new incoming message. The BMC typically returns a handshake character within one millisecond of 
being able to accept a new message, unless the controller has already initiated a message 
transmission or an operation such as firmware update. Note that the handshake character is used 
in the system for flow control and error detection. Even if unauthenticated IPMI messages are 
being rejected (or dropped) by the BMC, the BMC is expected to respond with a handshake to 
indicate its buffers are ready for a new incoming message. 
Figure 11 shows the message payload encapsulated with the serial start and stop bytes. 
Data byte Encoded sequence 
A0h AAh (ESC), B0h 
A5h AAh (ESC), B5h 
AAh AAh (ESC), BAh 
A6h AAh (ESC), B6h 
1Bh <ESC> AAh (ESC), 3Bh 



Open Compute Project  Open CloudServer OCS Chassis Management 
http://opencompute.org 35 
 
Request packet: 
rsAddress Function checksum rqAddress Seq cmd payload checksum
1 byte 1 byte 1 byte 1 byte 1 byte 1 byte n byte 1 byte
2 3 4 5 6 7 N N+1
Start 
(A0h)
1 byte
1
Stop
(A5h)
1 byte
N+2
 
Response packet: 
rqAddress Function checksum rsAddress Seq cmd completion
code checksumpayload
1 byte 1 byte 1 byte 1 byte 1 byte 1 byte 1 byte n byte 1 byte
2 3 4 5 6 7 8 N N+1
Start 
(A0h)
1 byte
1
Stop
(A5h)
1 byte
N+2
 
Sample framed request packet 
Get Chassis Status Request
0xA02000E08104017AA5 
Sample Request
 
Sample framed response packet 
Chassis Status Response
0xA081047B20040100011000507AA5
Handshake
0xA6
100 ms0 ms
Sample Response
 
Figure 11: Message payload encapsulated with the serial start and stop bytes 
5.4 Serial Console Redirection 
To support serial console redirection, a blade should support serial port sharing. 
Serial port sharing is a mechanism in which the BMC controls logic that lets a serial controller on 
the baseboard and a serial controller for the BMC share a single serial connector. To support serial 
console redirection, the blade BMC should be able to switch serial port control to and from the 
system baseboard. 



 
36 October 30, 2014 
 
Serial port sharing lets the IPMI basic mode messaging and system console redirection coexist on 
the same physical serial port. The BMC firmware should let the Set Serial/Modem Mux command 
switch the serial port from “BMC” to “SYS” for terminal console redirection. When the multiplexer 
(mux) is switched to the system (SYS), the firmware should snoop the in-bound traffic to detect 
IPMI message patterns for the IPMI Get Channel Authentication Capabilities and the Set 
Serial/Modem Mux (with switch to BMC parameters) commands. If it detects an IPMI message 
pattern matching Get Channel Authentication Capabilities or the Set Serial Modem Mux back to 
BMC, the BMC firmware should take control of the serial port from the system and respond to the 
IPMI message. The BMC firmware should retain control of the serial port until it receives a new 
request to switch control of the serial port back to the system. 
When the BMC has control of the serial port, the messaging protocol should comply with the 
Chassis Manager API (see Open CloudServer Chassis Manager user interface specification). When in 
console redirection mode, the system should support VT100 console output. 
Table 19 lists the conditions that determine the blade BMC behavior and the switching mechanism 
that enables the transitions between BMC messaging and console redirection. 
Table 19: Conditions causing switching 
Switching Conditions 
Switch to system  IPMI Set Serial/Modem Mux (to SYS) is received over serial  
Switch to BMC 
 IPMI Set Serial/Modem Mux (to BMC) is received over serial 
 The IPMI message Get Channel Authentication Capabilities is received over 
serial 
5.5 Chassis Manager Serial Port Session 
The Chassis Manager lets a client establish a serial port session to a target device (for example, a 
top of rack [TOR] network switch) that is physically connected to the Chassis Manager board. The 
Chassis Manager API provides four serial port session methods: StartSerialPortConsole, 
StopSerialPortConsole, SendSerialPortData, and ReceiveSerialPortData.  
Note that the serial port session API services devices attached to universal asynchronous 
receiver/transmitter (UART) 1, 2, 5, and 6. UART 4, which services blade devices populated in the 
chassis, uses a separate API. Note also that the ports allocated for the serial port session are COM 
1, 2, 5, and 6.  
Before attempting to communicate with the target device, the client should explicitly open a serial 
port session using StartSerialPortConsole with a parameter specifying the target serial 
port. The Chassis Manager will then attempt to open and initialize the target serial port. Currently, 



Open Compute Project  Open CloudServer OCS Chassis Management 
http://opencompute.org 37 
 
the serial baud rate supported for the serial port session is 9600 bps. When it receives the response 
for the StartSerialPortConsole request, the client must check the completion code to see 
if the serial port session has been successfully established. In addition, the client should use the 
session token stored in the response when issuing subsequent requests to the Chassis Manager 
throughout the session.  
When a serial port session has been successfully established, the client can issue commands to the 
target device using SendSerialPortData. The client can also receive data packets from the 
target device using ReceiveSerialPortData. Note that ReceiveSerialPortData is 
designed to operate asynchronously with SendSerialPortData, which means that the client 
can invoke ReceiveSerialPortData even if there is no preceding or matching invocation 
SendSerialPortData. The asynchronous design ensures that the client can reliably receive the 
data packets sent by the target device even without an explicit command (for example, console 
output messages generated while the target device is booting up). 
After all the packets of interest have been communicated, the client should explicitly close the 
session with StopSerialPortConsole. The Chassis Manager will then release the target serial 
port and make it available for other clients. 
5.6 Command Completion Codes 
Table 20 lists the completion codes, follows the IPMI 2.0 completion codes. 
Table 20: Command-completion codes 
Code Description 
Generic completion codes (00h, C0h-FFh) 
00h   Command completed normally 
C0h  
 Node busy 
 Command could not be processed because command processing resources are 
temporarily unavailable 
C1h  
 Invalid command  
 Used to indicate an unrecognized or unsupported command 
C2h   Command invalid for given logical unit number (LUN) 
C3h  
 Timeout while processing command 
 Response unavailable 



 
38 October 30, 2014 
 
Code Description 
C4h  
 Out of space 
 Command could not be completed because of a lack of storage space required to 
execute the given command operation 
C5h   Reservation canceled or invalid reservation ID 
C6h   Request data truncated 
C7h   Request data length invalid 
C8h   Request data field length limit exceeded 
C9h  
 Parameter out of range 
 One or more parameters in the data field of the request are out of range (different 
from the invalid data field [CCh] code in that it indicates that the erroneous field(s) has 
a contiguous range of possible values) 
CAh   Cannot return number of requested data bytes 
CBh   Requested sensor, data, or record not present 
CCh   Invalid data field in request 
CDh   Command illegal for specified sensor or record type 
CEh   Command response could not be provided 
CFh  
 Cannot execute duplicated request 
 This completion code is for devices which cannot return the response that was 
returned for the original instance of the request; such devices should provide separate 
commands that allow the completion status of the original request to be determined 
 An event receiver does not use this completion code, but returns the 00h completion 
code in the response to (valid) duplicated requests  
D0h   Command response could not be provided; SDR repository in update mode 
D1h   Command response could not be provided; device in firmware update mode 
D2h   Command response could not be provided; BMC initialization or initialization agent in 
progress 
D3h  
 Destination unavailable; cannot deliver request to selected destination (for example, 
this code can be returned if a request message is targeted to SMS but the receive 
message queue reception is disabled for the particular channel) 
D4h   Cannot execute command due to insufficient privilege level or other security-based 
restriction (for example, disabled for firmware firewall) 



Open Compute Project  Open CloudServer OCS Chassis Management 
http://opencompute.org 39 
 
Code Description 
D5h  
 Cannot execute command 
 Command, or request parameter(s), not supported in present state 
D6h  
 Cannot execute command 
 Parameter is illegal because command sub -function has been disabled or is unavailable 
(for example, disabled for firmware firewall) 
FFh  Unspecified error 
Device-specific (OEM) codes (01h-7Eh) 
01h-7Eh  
 Device-specific (OEM) completion codes 
 This range is used for command-specific codes that are also specific to a particular 
device and version (prior knowledge of the device command set is required for 
interpretation) 
Command-specific codes (80h-BEh) 
80h-BEh  
 Standard command-specific codes 
 This range is reserved for command-specific completion codes for commands specified 
in this document 
5.7 Blade Command Payload 
The Chassis Manager protocol payload carries the blade commands, as shown in Figure 12. 
rqAddress
 Function
 checksum
 rsAddress
 Seq
 cmd
 completion
code
 checksum
payload
1 byte 1 byte 1 byte 1 byte 1 byte 1 byte 1 byte n byte 1 byte
2 3 4 5 6 7 8 N N+1
Start 
(A0h)
1 byte
1
Stop
(A5h)
1 byte
N+2
Payload
 
Figure 12: Chassis Manager payload 
Certain support commands are required for blade identification and session establishment. The 
following commands should always be accepted by the blade, whether sent outside of an active 
session or within the context of an active session: 
 Get System GUID  
 Get Channel Authentication Capabilities 
 Get Session Challenge 
 Activate Session 



 
40 October 30, 2014 
 
5.7.1 Blade Identification Commands 
The Get Channel Authentication Capabilities command is used to identify the blade type (compute 
or JBOD). A blade should respond to this command before and after a session has been established. 
The response message should use byte 9 (OEM auxiliary data) to advertise the blade type: 0x04 for 
compute or 0x05 for storage. When response message byte 9 is combined with the OEM ID (bytes 
6:8), the Chassis Manager will know both the OEM and type of blade.  
Compute blade implementations are required to support session-based authentication, while JBOD 
blades are not required to support-session based authentication. A blade advertises its 
authentication support through the Get Channel Authentication Capabilities command, byte 3 and 
byte 4. If a JBOD blade does not support authentication, then byte 3 and byte 4 should equal zero. 
If authentication is not supported on a JBOD blade, all mandatory (M) IPMI commands listed in this 
specification should be supported without a session initialization processes.    
Note that user session-based authentication is required for all OCS system compute blades. Per-
message-based authentication is not supported because session headers are not support over 
serial IPMI. 
5.7.2 Session Establishment Commands 
Before general messaging can occur, a session must be activated through a set of session setup 
commands: Activate Session, Get Session Challenge, and Set Session Privilege Level. These 
commands can be thought of as always being unauthenticated. Note that Activate Session is the 
first, and in some cases only, authenticated command for a session. Figure 13 shows the process. 
 



Open Compute Project  Open CloudServer OCS Chassis Management 
http://opencompute.org 41 
 
1
2
3
4
5
6
Get Session
Challenge, Rq
Get Session
Challenge, Rs
Activate 
Session, Rq
Activate 
Session, Rs
Session Privilege 
Level, Rq
Session Privilege 
Level, Rs
Chassis
Manager
Blade
BMC
 
Figure 13: Session establishment process 
The following steps are used to establish a session: 
1. The Chassis Manager sends a Get Channel Authentication Capabilities to the blade to get 
information about the blade type and session authentication support.  
If sessions are supported, the Chassis Manager advances to step 2.   
If the blade is a session-less JBOD (some JBOD blades require no authentication or session 
establishment), the Chassis Manager skips steps 2-7 during the initialization process. 
2. The Chassis Manager sends a Get Session Challenge request to the BMC with an authentication 
type of “none” and a username that selects which set of user information should be used for 
the session (UserId 1, if default account is UserId 0). This is the only place where the username 
is used during the process.  
3. The BMC looks up the user information associated with the username. If the user is found and 
allowed access via the given channel, the BMC returns a Get Session Challenge response that 
includes a randomly generated challenge string and a temporary session ID. The BMC keeps 
track of the username associated with the session ID; the session ID is used to look up the 
user’s information in step 4.  



 
42 October 30, 2014 
 
4. The Chassis Manager then issues an Activate Session request. The request contains the 
temporary session ID plus the authentication information (None). (For example, the 
serial/modem connection might only pass a simple clear-text password in the activate session 
data.) The authentication format for different authentication types is specified in the 
description of the Activate Session command. Note that the WCS system specification only 
supports authentication type None (0x00).   
5. The BMC uses the temporary session ID to look up the information for the user identified in the 
Get Session Challenge request (for example, the user’s password/key data and a stored copy of 
the earlier challenge string) and uses it to verify that the packet signature or password is 
correct.  
6. The Chassis Manager then sends a Set Session Privilege Level command to the BMC. This 
command is sent in authenticated format. After the session is activated, the session is set to an 
initial privilege level. A session that is activated is initially set to USER level, regardless of the 
maximum privilege level requested in the Activate Session command. The Chassis Manager 
must raise the privilege level of the session using this command to execute commands that 
require a higher level of privilege.   
7. The BMC looks up the privilege level set for the user. If the privilege level requested matches 
the level set for the user, the BMC responses to the Chassis Manager Set Session Privilege 
Level with a positive completion code. Note that Set Session Privilege Level cannot be used to 
set a privilege level higher than the lowest of the privilege level set for the user. 
5.7.3 Session Termination 
If the blade BMC supports IPMI single-session serial connections and a session is established, the 
BMC should accept a Close Session command and immediately terminate the session, freeing up 
resources for another session to be established.  
If a session is not closed using Close Session, the session should time out and close itself after a 
specified time interval. This time interval should be configurable with the Set Serial/Modem 
Configuration command. (Note that the IPMI firmware should support all Set Serial/Modem 
Configuration command parameters defined in this specification.)  
If the Chassis Manager follows the sequence described in 5.7.2 above to establish a new session 
without sending a Close Session, or before the time out interval for the current session has expired, 
the blade BMC should always terminate the previous session and allow a new session to be 
established. The Activate Session should always complete successfully to establish a new session. 



Open Compute Project  Open CloudServer OCS Chassis Management 
http://opencompute.org 43 
 
5.8 Command Formats 
The following sections describe the formats of the Chassis Manager protocol payload commands. 
Note that the following sections copy command formats from the IPMI 2.0 specification. In addition 
to IPMI-defined command formats, this section details system-defined OEM commands and 
modifications to IPMI command payloads, such as the Get Channel Authentication Capabilities 
command. 
5.8.1 Get Device ID 
Refer to the IPMI 2.0 specification. 
5.8.2 Get System GUID 
Refer to the IPMI 2.0 specification. 
5.8.3 Get Channel Authentication Capabilities 
The blade should respond to the Get Channel Authentication Capabilities command outside of an 
active session. The command can also be executed within the context of an active session.    
Note: Byte 9 is a purposeful deviation from the IPMI 2.0 specification. 
Table 21 describes the Get Channel Authentication Capabilities command request. 
Table 21: Get channel authentication capabilities command request 
Byte Description 
1 Channel number  
[7] – 1b = get IPMI v2.0+ extended data  
If the given channel supports authentication but does not support RMCP+ (for example, a 
serial channel), then the response data should return with bit [5] of byte 4 = 0b, and byte 5 
should return 01h  
0b = Backward compatible with IPMI v1.5  
Result response data only returns bytes 1:9, bit [7] of byte 3 (authentication type support) 
and bit [5] of byte 4 returns as 0b, bit [5] of byte byte 5 returns 00h.   
[6:4] – reserved  
[3:0] – channel number 
0h-7hBh, Fh = channel numbers  
Eh = retrieve information for channel this request was issued on. 



 
44 October 30, 2014 
 
Byte Description 
2 Requested maximum privilege level 
[7:4] – reserved 
[3:0] – requested privilege level 
0h = reserved 
1h = Callback level 
2h = User level 
3h = Operator level 
4h = Administrator level 
5h = OEM proprietary level 
Table 22 describes the Get Channel Authentication Capabilities command response. 
Table 22: Get channel authentication capabilities command response 
Byte Description 
1 Completion code 
2 Channel number 
Channel number that the authentication capabilities are being returned for.  
If the channel number in the request was set to Eh, this will return the channel number on 
which the request was received 
3 Authentication type support 
Returns the setting of the authentication type enable field from the configuration 
parameters for the given channel that corresponds to the requested maximum privilege 
level 
[7] -  1b = IPMI v2.0+ extended capabilities available (See extended capabilities field below) 
0b = IPMI v1.5 support only 
[6] -  reserved 
[5:0] -  IPMI v1.5 authentication type(s) enabled for given requested maximum privilege 
level 
All bits:  1b = supported 
0b = authentication type not available for use. 
[5] -  OEM proprietary (per OEM identified by the IANAOEM ID in the RMCPPing Response) 
[4] -  straight password / key 
[3] -  reserved 
[2] -  MD5 



Open Compute Project  Open CloudServer OCS Chassis Management 
http://opencompute.org 45 
 
Byte Description 
[1] -  MD2 
[0] -  none 
4 [7:6] – reserved 
[5] - KG status (two-key login status). Applies to v2.0/RMCP+ RAKP authentication only 
(otherwise, ignore as “reserved”) 
0b = KG is set to default (all 0’s). User key KUID will be used in place of KG in RAKP 
(knowledge of KG not required for activating session) 
1b = KG is set to non -zero value (knowledge of both KG and user password (if not 
anonymous login) required for activating session) 
The following bits apply to IPMI v1.5 and v2.0: 
[4] -Per-message authentication status  
0b = Per-message authentication is enabled; packets to the BMC must be authenticated per 
authentication type used to activate the session and user level authentication setting 
1b = Per-message authentication is disabled; Authentication Type is “none” accepted for 
packets to the BMC after the session has been activated. 
[3] -  User Level Authentication status 
0b = User Level Authentication is enabled. User Level commands must  
be authenticated per Authentication Type used to activate the session. 
1b = User Level Authentication is disabled. Authentication Type “none” is accepted for User 
Level commands to the BMC. 
[2:0] -Anonymous Login status; this parameter returns values that tells the remote console 
whether there are users on the system that have “null” usernames. This can be used to 
guide the way the remote console presents login options to the user. (see IPMI v1.5 
specification sections  6.9.1, “Anonymous Login” Convention and 6.9.2, Anonymous Login) 
[2] -  1b = Non-null usernames enabled. (One or more users are enabled that have non-null 
usernames). 
[1] -  1b = Null usernames enabled (One or more users that have a null username, but non-
null password, are presently enabled) 
[0] -  1b = Anonymous Login enabled (A user that has a null username and null password is 
presently enabled) 
5 For IPMI v1.5: -reserved 
For IPMI v2.0+: -extended capabilities 
[7:2] -  reserved 
[1] -    1b = channel supports IPMI v2.0 connections. 
[0] -    1b = channel supports IPMI v1.5 connections 



 
46 October 30, 2014 
 
Byte Description 
6:8 OEM ID Identification bytes:  
IANA Enterprise number for OEM/organization.  
This field must return an OEM Id irrespective of authentication type available.  
9 Compute blade = 0x04,  JBOD blade = 0x05 
5.8.4 Get Session Challenge 
Refer to the IPMI 2.0 specification. 
5.8.5 Activate Session  
Refer to the IPMI 2.0 specification. 
5.8.6 Set Session Privilege Level 
Refer to the IPMI 2.0 specification. 
5.8.7 Close Session 
Refer to the IPMI 2.0 specification. 
5.8.8 Get Message 
Refer to the IPMI 2.0 specification. 
5.8.9 Send Message 
Refer to the IPMI 2.0 specification. 
5.8.10 Get Chassis Status 
Refer to the IPMI 2.0 specification. 
5.8.11 Chassis Control 
Refer to the IPMI 2.0 specification. 
5.8.12 Chassis Identify 
Refer to the IPMI 2.0 specification. 
5.8.13 Set Power Restore Policy 
Refer to the IPMI 2.0 specification. 



Open Compute Project  Open CloudServer OCS Chassis Management 
http://opencompute.org 47 
 
5.8.14 Set Power Cycle Interval 
Refer to the IPMI 2.0 specification. 
5.8.15 Set System Boot Options 
Refer to the IPMI 2.0 specification. 
5.8.16 Get System Boot Options 
Refer to the IPMI 2.0 specification. 
5.8.17 Get Sensor Reading Factors 
Refer to the IPMI 2.0 specification. 
5.8.18 Get Sensor Reading 
Refer to the IPMI 2.0 specification. 
5.8.19 Get Sensor Type 
Refer to the IPMI 2.0 specification. 
5.8.20 Read FRU Data 
Refer to the IPMI 2.0 specification.  Offset should be in bytes no WORD.  Fru Inventory Area Info 
command is not required. 
5.8.21 Write FRU Data 
Refer to the IPMI 2.0 specification. Offset should be in bytes no WORD.  Fru Inventory Area Info 
command is not required. 
5.8.22 Reserve SDR Repository 
Refer to the IPMI 2.0 specification. 
5.8.23 Get SDR 
Refer to the IPMI 2.0 specification.  
Note: Sensor types supported are Full (01h), Compact (02h), and Event Only (03h). 
5.8.24 Reserve SEL 
Refer to the IPMI 2.0 specification. 
The reservation process provides a limited amount of protection when records are being deleted or 
incrementally read.   



 
48 October 30, 2014 
 
A Reservation ID value is returned in response to this command. This value is required in other 
requests, such as the Clear SEL command (commands will not execute unless the correct 
Reservation ID value is provided).  
As an example, if the Chassis Manager wants to clear the SEL, it first reserves the repository by 
issuing a Reserve SEL command. The application checks to see if all SEL entries have been handled 
before issuing the Clear SEL command. If a new event had been placed in the SEL after the records 
were checked but before the Clear SEL command, it is possible for the event to be lost. However, 
the addition of a new event to the SEL causes the present Reservation ID to be canceled, preventing 
the Clear SEL command from executing. The Chassis Manager can then repeat the reserve-check-
clear process until it succeeds. 
5.8.25 Get SEL Entry 
Refer to the IPMI 2.0 specification. 
5.8.26 Add SEL Entry 
Refer to the IPMI 2.0 specification. 
5.8.27 Clear SEL 
Refer to the IPMI 2.0 specification. 
5.8.28 Set Serial/Modem Mux 
The Set Serial/Modem Mux command switches control of the IPMI serial port to the system for 
console redirection. The command must response to the request message before transferring 
control of the serial port to the system for console redirection. 
Refer to the IPMI 2.0 specification. 
5.8.29 Get Power Reading  
Refer to the DCMI 1.5 specification. 
5.8.30 Get Power Limit 
Refer to the DCMI 1.5 specification. 
5.8.31 Set Power Limit  
Refer to the DCMI 1.5 specification. 
5.8.32 Activate Power Limit  
Refer to the DCMI 1.5 specification. 



Open Compute Project  Open CloudServer OCS Chassis Management 
http://opencompute.org 49 
 
5.8.33 Get Processor Info 
The Get Processor Info command returns the processor type and status.  
Table 23 describes the Get Processor Info request. 
Table 23: Get Processor Info request 
Table 24 describes the Get Processor Info response. 
Table 24: Get Processor Info response 
Bytes Description 
1 Completion code 
2 Processor type (see Table 60) 
3:4 Processor frequency (in MHz); LSB first 
5 Processor status: 
01h is present 
FFh is not present 
Table 25 lists the processor types. 
Table 25: Processor types 
Byte Description 
1 Processor index (0-based index) 
Code Processor make and model Code Processor make and model 
00h Celeron (Intel)  0Eh Lynnfield (Intel) 
01h Pentium III (Intel) 0Fh Lisbon (AMD) 
02h Pentium 4 (Intel)  10h Phenom II (AMD) 
03h Xeon (Intel)  11h Athlon II (AMD) 
04h Prestonia (Intel)  12h Operaton (AMD) 
05h Nocona (Intel)  13h Suzuka (AMD) 
06h Opteron (AMD)  14h Core i3 (Intel) 
07h Dempsey (Intel)  15h 
Intel® Xeon™® Processor Family E5-
2600v1 product family 
08h Clovertown (Intel)  16h Intel® Xeon™ E5-2600 v2 product 



 
50 October 30, 2014 
 
5.8.34 Get Memory Info 
The Get Memory Info command returns information about a given memory DIMM. The command 
uses 1-based indexing.  
If zero is used as the DIMM index input parameter, the response message will follow Table 26. 
Table 26. Get Memory Info response (if zero index as DIMM index) 
Bytes Description 
1 Completion code 
2 DIMM slot number 
3 DIMM presence info in bit map for DIMM1 to DIMM8 
4 DIMM presence info in bit map for DIMM9 to DIMM16 
Table 27 describes the Get Memory Info request. 
Table 27: Get Memory Info request 
Table 28 describes the Get Memory Info response. The BMC should return 0x3F in byte 2 and 0x03 
in byte 7 when no valid information is available about the DIMM. After the BIOS has updated the 
BMC with the correct DIMM information, the information should be stored in persistent memory. 
BMC should return the information from the previous POST even when the blade is turned off.  
During power up, BMC should return the stored memory information until the BIOS has updated 
the BMC with the new memory information. 
family(Intel) 
09h Tigerton (Intel)  17h 
Intel® Atom™ Processor S1200 
product family 
0Ah Dunnington (Intel)  18h 
Intel® Xeon™® Processor E5-2600 v3 
product family 
0Bh Harpertown (Intel) FFh No CPU present 
Byte Description 
1 DIMM index (1-based index) 



Open Compute Project  Open CloudServer OCS Chassis Management 
http://opencompute.org 51 
 
Table 28: Get Memory Info response (1+ index as DIMM index) 
Bytes Description 
1 Completion code 
2 Bit[5]: Type 
00h: SDRAM 
01h: DDR-1 RAM 
02h: Rambus 
03h: DDR-2 RAM 
04h: FBDIMM 
05h: DDR-3 RAM 
06h: DDR-4 RAM 
0Ah: DDR-4 NVDIMM with Supercap 
3Fh: No DIMM present  
3:4 DIMM speed (in MHz); LSB first 
5:6 DIMM size (in Megbytes); LSB first 
7 DIMM status: 
00h: Reserved 
01h: Unknown DIMM type 
02h: Ok 
03h: Not present 
05h: Single bit error 
07h: Multi bit error 
5.8.35 Get PCIe Info 
The Get PCIe Info command returns the device type using 1-based indexing. If zero is used as the 
PCIe index input parameter, the response message will follow Table 29 for the slot mapping.  
Table 29: PCIe slot mapping 
Index Location Supported devices 
1 LAN_MEZZ CX3 or other LAN mezzanine-card 
2 
Tray backplane PCIe slot 
PCIex16 PCIex8 PCIex4 
3   PCIex4 
4  PCIex8 PCIex4 
5   PCIex4 
6 
PCIe_slot 1 
PCIex8 PCIex4  
7 N/A PCIex4  



 
52 October 30, 2014 
 
Table 30 describes the Get PCIe Info request. 
Table 30: Get PCIe Info request 
Table 31 describes the Get PCIe Info response to an index of zero. 
Table 31: Get PCIe Info response 
Bytes Description 
1 Completion code 
2 PCIe Presence info in bit map for Slot 1 to Slot 8 
3 [4:0] PCIe Presence info in bit map for Slot 9 to Slot 13 
[7:5] Reserved – written as not present 0b. 
Table 32 describes the Get PCIe Info response to non-zero based index. For non-existent devices, 
the command should complete successfully with Vendor ID, Device ID, Subsystem Vendor ID, and 
Subsystem ID all set to 0xFFFF. 
Table 32: Get PCIe Info response 
Bytes Description 
1 Completion code 
2:3 Vendor ID; LSB 
4:5 Device ID; LSB 
6:7 Subsystem Vendor ID; LSB 
8:9 Subsystem ID; LSB 
5.8.36 Get NIC Info 
The Get NIC Info command returns the device type and status.  
8 
PCIe_slot 2 
PCIex8 PCIex4  
9 N/A PCIex4  
10 
PCIe_slot 3 
PCIex8 PCIex4  
11 N/A PCIex4  
12 
PCIe_slot 4 
PCIex8 PCIex4  
13 N/A PCIex4  
Byte Description 
1 PCIe Slot Index (1-based index) for PCIe. An index of zero will return the slot mapping. 



Open Compute Project  Open CloudServer OCS Chassis Management 
http://opencompute.org 53 
 
Table 33 describes the Get NIC Info request. 
Table 33: Get NIC Info request 
Table 34 describes the Get NIC Info response. A completion code of 0xCC should be returned for a 
NIC index with no NIC installed. 
Table 34: Get NIC Info response 
5.8.37 BMC Debug 
The BMC Debug command enables the output of KCS and serial command trace debug messages in 
the BMC diagnostic debug console.  
Table 35 describes the BMC Debug request. 
Table 35: BMC Debug request 
Table 36 describes the BMC Debug response. 
Table 36: BMC Debug response 
5.8.38 Get BIOS Code 
The Get BIOS Code command returns the BIOS post code history. The history will be stored in 
memory allocated by the SNOOP driver. It will assign a total of 512 bytes for the current and 
Byte Description 
1 NIC index (0-based index) 
Bytes Description 
1 Completion code 
2:7 6-byte MAC address 
Byte Description 
1 Process: 
0xFD =  All KCS and serial command trace debug messages 
0xFC =  Fan control function trace debug messages 
2 Enable/Disable: 
0 = Disable (default) 
1 = Enable 
Byte Description 
1 Completion code 



 
54 October 30, 2014 
 
previous post code.  When the system is reset the driver starts to record the current BIOS post 
code. Table 37 describes the Get BIOS Code request. 
Table 37: Get BIOS Code request 
Table 38 describes the Get BIOS Code response. 
Table 38: Get BIOS Code response 
5.8.39 Get Disk Status 
The Get Disk Status command returns the status of each disk in the JBOD. Each disk will add 1 byte 
to the response (see byte 4+ in the response below). The byte that represents the disk will be split, 
with bits 7-6 representing the disk status and bits 5-0 representing the unique disk number.  
The channel parameter in the request packet is used to select the target SAS controller/disk 
backplane for JBODs. The Get Disk Status command uses NetFn: 2Eh/2Fh and command identifier 
C4h. 
Table 39 describes the Get Disk Status request. 
Table 39: Get Disk Status request 
Byte Description 
1 Command: 
0 = Read current BIOS code 
1 = Read previous BIOS code 
Byte Description 
1 Completion code 
00h = Success 
CCh = Invalid data field 
C1h = Invalid command 
07h=File error 
2:257 BIOS code 
Stream of BIOS code in hexadecimal value 
Byte Description 
1 [7:0] – reserve for channel number 0x00 



Open Compute Project  Open CloudServer OCS Chassis Management 
http://opencompute.org 55 
 
Table 40 describes the Get Disk Status response. 
Table 40: Get Disk Status response 
Bytes Description 
1 Completion code  
2 Channel number 
Default for this specification is 0x00 
3 Disk count (total number of disks) 
4+N 7-6: disk status 
0=normal, 1=failed, 2=error 
5-0: disk number  
Disk number/location ID 
5.8.40 Get Disk Info 
The Get Disk Info command returns sensor information regarding disks in the JBOD such as 
temperature.  
To conform with the communication protocol this command uses OEM-reserved IPMI commands: 
 The Get Disk Status command uses NetFn: 2Eh/2Fh and command identifier C5h. 
 The Get Disk Temperature command is expected to return the status of each disk in the JBOD if 
disk temperatures are available. If not available, the command should report the JBOD 
temperature. The multiplier byte in the response message will be multiplied against the MS 
byte of the reading to assist in storing large and negative numbers. 
Table 41 describes the Get Disk Info request. 
Table 41: Get Disk Info request 
Table 42 describes the Get Disk Info response. 
Table 42: Get Disk Info response 
Bytes Description 
1 IPMI completion code  
2 Reading unit (see IPMI table)  
Byte Description 
1 Channel number 
00h for single channel 
2 Disk number (if per-disk temperatures are available, otherwise 00h got JBOD) 



 
56 October 30, 2014 
 
Bytes Description 
3 MS byte multiplier (byte 4); byte should represent unsigned int 
[7] 1b = negative multiplier 
0b = positive multiplier 
[6-0] reading MS byte multiplier 
4 Reading LS byte first 
5 Reading MS byte 
Following are examples of disk packets: 
Request Packet: 
0xA0202EB28104C50000B6A5 
Example Response Packet for 32.00 degrees C: 
A0812F502004C50001000020F6A5 
Example Response Packet for -5.02 degrees C: 
A0812F502004C500018102058EA5  
5.8.41 Network Controller BIOS Integration 
The IPMI command requires BIOS interaction to receive the NIC MAC address. BIOS is responsible 
for communicating the Network Interface Controller MAC address to the BMC in support of the Get 
NIC Info command. 
 
The BIOS should provide the BMC the MAC address information for each network controller.  The 
BIOS should retrieve the MAC address information from the network controller using the UEFI 
EFI_SIMPLE_NETWORK_PROTOCOL data structure. 
5.8.42 Sensor Data Repository 
The first record in the Sensor Data Repository should be the Fan duty cycle: ReqDutyCycle. The 
Sensor Data Record Formats supported by the Chassis Manager are: Full Sensor Record (0x01) 
Compact Sensor Record (0x02) and Event Only (0x03). 
SDR Entity’s and entity IDs should adhere to the IPMI 2.0 Specification and uniquely identify a 
physical entity and instance or logical group of entities and instances within the system: 
IPMI 2.0 - 39: “An Entity Id is a standardized numeric code that is used in SDRs to identify the types 
of physical entities or FRUs in the system. The codes include values for entities such as Processor, 



Open Compute Project  Open CloudServer OCS Chassis Management 
http://opencompute.org 57 
 
Power Supply, Fan, etc. The Entity ID values are specified in IPMI 2.0 Specification Table 43-13, 
Entity Id Codes. 
 The Entity ID is associated with an Entity Instance value that is used to indicate the particular 
instance of an entity. For example, a system with four processors would use an Entity Instance 
value of ‘0’ to identify the first processor, ‘1’ for the second, and so on” 
Entity Instance values are zero-based. For example, the first temperature sensor will have Entity 
Instance 0x00. 
DIMM temperature sensors should be aggregated by channel. For example, Temp_DIMM_A0 and 
Temp_DIMM_A1 should be aggregated into one sensor, i.e. Temp_DIMM_A. 
The mezzanine temperature sensor (Temp_Mezz) has a slave address of 0x98 and uses the Texas 
Instruments TMP411 temperature sensor.  When the Tray Mezz FPGA control is present, this sensor 
should be included in the thermal control algorithm for calculating PWM.   In addition to the TI 
TMP411 sensor, there is an additional sensor at address 0xEE (7’b1110_1110).  This temperature 
module returns an 8-bit signed integer with a direct mapping to Celsius (i.e. values [-128, 127] 
implies [-128°C, 127°C]).  This sensor should be included in the SDR, but not form part of the PWM 
calculation. 
The following table shows a sample of a SDR table. 
Table 43. Sample SDR: 
Sensor name Record 
ID 
Sensor 
number 
Sensor 
type 
Sensor 
format Event reading Entity 
ID 
Entity 
instance 
ReqDutyCycle 0x01 0x01 0x04 0x01 Threshold 0x1D 0x01 
Temp_Inlet 0x04 0xB0 0x01 0x01 Threshold 0x07 0x00  
Temp_Outlet 0x05 0xB1 0x01 0x01 Threshold 0x07 0x01  
Temp_Mezz 0x03 0x39 0x01 0x01 Threshold 0x07 0x09 
Temp_Mezz_Ctrl 0x3E 0x3A 0x01 0x01 Threshold 0x07 0x0A 
Temp_CPU0 0x06 0xB2 0x01 0x01 Threshold 0x03 0x00  
Temp_CPU1 0x07 0xB3 0x01 0x01 Threshold 0x03 0x01  
Temp_DIMM_A 0x08 0xB4 0x01 0x01 Threshold 0x20 0x80  
Temp_DIMM_B 0x09 0xB5 0x01 0x01 Threshold 0x20 0x81 
Temp_DIMM_C 0x0A 0xB6 0x01 0x01 Threshold 0x20 0x82 
Temp_DIMM_D 0x0B 0xB7 0x01 0x01 Threshold 0x20 0x83 



 
58 October 30, 2014 
 
Sensor name Record 
ID 
Sensor 
number 
Sensor 
type 
Sensor 
format Event reading Entity 
ID 
Entity 
instance 
Temp_DIMM_E 0x0C 0xB8 0x01 0x01 Threshold 0x20 0x84 
Temp_DIMM_F 0x0D 0xB9 0x01 0x01 Threshold 0x20 0x85 
Temp_PCH 0x0E 0xBA 0x01 0x01 Threshold 0x2D 0x00  
P3V3 0x0F 0xC4 0x02 0x01 Threshold 0x07 0x02  
P5V 0x10 0xC5 0x02 0x01 Threshold 0x07 0x03  
PVDDQ_ABC 0x11 0xC6 0x02 0x01 Threshold 0x20 0x86  
PVDDQ_DEF 0x12 0xC7 0x02 0x01 Threshold 0x20 0x87 
P1V2 0x13 0xC8 0x02 0x01 Threshold 0x07 0x04  
P1V1_SSB 0x14 0xC9 0x02 0x01 Threshold 0x07 0x05  
P12V 0x15 0xCA 0x02 0x01 Threshold 0x07 0x0A  
PV_VCCP_CPU0 0x16 0xCB 0x02 0x01 Threshold 0x03 0x00  
PV_VCCP_CPU1 0x17 0xCC 0x02 0x01 Threshold 0x03 0x01 
P12V_AUX 0x18 0xCD 0x02 0x01 Threshold 0x07 0x07  
HSC Input Power 0x19 0x28 0x0B 0x01 Threshold 0x0A 0x00  
HSC Input Volt 0x1A 0xCF 0x02 0x01 Threshold 0x0A 0x01  
HSC Status 0x1B 0x29 0x08 0x02 SensorSpecific 0x0A 0x02  
CPU0_PROC_HOT 0x21 0xBB 0x01 0x02 Discrete 0x03 0x00  
CPU1_PROC_HOT 0x22 0xBC 0x01 0x02 Discrete 0x03 0x01 
PVCCP_CPU0_VRHOT 0x23 0xBD 0x01 0x02 Discrete 0x03 0x00  
PVCCP_CPU1_VRHOT 0x24 0xBE 0x01 0x02 Discrete 0x03 0x01 
PVDQ_ABC_VRHOT 0x25 0xBF 0x01 0x02 Discrete 0x08 0x80  
PVDQ_DEF_VRHOT 0x26 0xC0 0x01 0x02 Discrete 0x08 0x83 
CPU0_MEM01_HOT 0x27 0xC1 0x01 0x02 Discrete 0x20 0x88  
CPU1_MEM01_HOT 0x28 0xC2 0x01 0x02 Discrete 0x20 0x89 
SSB ThermalTrip 0x29 0xC3 0x01 0x02 Discrete 0x07 0x08  
Watchdog 0x2A 0x93 0x23 0x02 SensorSpecific 0x06 0x00  
SEL 0x2B 0x8A 0x10 0x02 SensorSpecific 0x06 0x01  



Open Compute Project  Open CloudServer OCS Chassis Management 
http://opencompute.org 59 
 
Sensor name Record 
ID 
Sensor 
number 
Sensor 
type 
Sensor 
format Event reading Entity 
ID 
Entity 
instance 
System Event 0x2C 0x83 0x12 0x02 SensorSpecific 0x06 0x02  
CPU0 0x2D 0xD3 0x07 0x02 SensorSpecific 0x03 0x00  
CPU1 0x2E 0xD4 0x07 0x02 SensorSpecific 0x03 0x01 
CPU_ERROR 0x2F 0xD5 0x07 0x02 SensorSpecific 0x03 0x82 
Memory 0x30 0x87 0x0C 0x02 SensorSpecific 0x20 0x8A 
POST Error 0x31 0x9E 0x0F 0x02 SensorSpecific 0x22 0x00  
PCI-E BUS 0x32 0xA1 0x13 0x02 SensorSpecific 0x31 0x00  
CPU IIO Err 0x33 0xA7 0x07 0x02 SensorSpecific 0x03 0x83 
CPU QPI Error 0x34 0x9D 0x07 0x02 SensorSpecific 0x03 0x84 
System Power 0x35 0x2A 0x09 0x02 SensorSpecific 0x13 0x00  
ME Pwr Mode 0x36 0xFC 0x16 0x0A Discrete 0x2E 0x06  
SPS FW Health 0x37 0x17 0xDC 0x75 Discrete 0x2E 0x00  
NM Exception 0x38 0x18 0xDC 0x72 Discrete 0x2E 0x02  
NM Health 0x39 0x19 0xDC 0x73 Discrete 0x2E 0x01  
NM Capabilities 0x3A 0x1A 0xDC 0x74 Discrete 0x2E 0x04  
NM Threshold 0x3B 0x1B 0xDC 0x72 Discrete 0x2E 0x03  
 
5.8.43 Hardcoded Sensor Numbers 
The following sensor numbers are fixed for WCS. The BMC should use the sensor numbers specified 
in the following table. 
Table 44: Hardcoded sensor numbers: 
Sensor name Sensor number Sensor type 
ReqDutyCycle 0x01 0x04 (Fan) 
Temp_Inlet 0xB0 0x01 (Temperature) 



 
60 October 30, 2014 
 
6 Chassis Manager REST API 
The sections that follow describe the Chassis Manager Rest API. 
6.1 User Roles and API Access 
The Chassis Manager web service provides a full set of security features, including encryption, 
integrity, authentication, and fine-grained API-level authorization. 
6.2 Encryption and Service Credentials 
All data communication between the Chassis Manager web service and clients (web browser or 
command-line interface) is encrypted using secure socket layers (SSL).  The system uses signature-
based checksum (signed packets) to prevent tampering and sends data secure HTTP (HTTPS) to 
ensure integrity. The Chassis Manager web service is also authenticated against the client using 
Microsoft Certificate Services. 
6.3 Client Credentials/Authentication 
Client authentication is based on either machine-local or domain-user Windows credentials. Client 
Windows credentials are automatically obtained from the client computer based on the context of 
the logged-in user. 
6.4 Role-Based API-Level Authorization 
Client authorization to the Chassis Manager web service is provided at the granularity of the service 
APIs. The Chassis Manager APIs are categorized into three security domains:  
 U1─APIs that perform Chassis Manager management functions and manage devices that are 
connected to the Chassis Manager (for example, blades and power supply units).  
 U2─APIs that manage devices (for example, blades and power supply units) that are connected 
to the Chassis Manager. 
 U3─APIs that perform only read-only operations. 
Note: U1 includes all Chassis Manager APIs, while U2 and U3 include only a subset of the Chassis 
Manager APIs. Note also that U3 is a subset of U2, which is a subset of U1. 
Users authorized to perform Chassis Manager functions can be categorized into three Windows 
security domains or groups: 



Open Compute Project  Open CloudServer OCS Chassis Management 
http://opencompute.org 61 
 
 AcsCmAdmin─Users in this group are authorized to perform functions in U1. They have access 
to all APIs, including APIs for Chassis Manager management functions like “add-user” and “set-
NIC.” 
 AcsCmOperator─Users in this group are authorized to perform functions in U2, and have access 
to all APIs except those for Chassis Manager management functions. 
 AcsCmUser─Users in this group are authorized to perform functions in U3, and can only access 
read-only APIs. 
Any user attempting to access the Chassis Manager APIs will be authorized based on their role or 
group. Users who do not belong to any of the three authorization roles or groups are denied access 
to Chassis Manager API functionalities. 
The three Windows groups are available in each Chassis Manager, and local Chassis Manager users 
can be assigned to any of the three local roles (CM-1/AcsCmAdmin, CM-1/AcsCmOperator, and CM-
1/AcsCmUser) using the “add user” and “change user” APIs.  
The three authorization roles can also be created in each domain that wants to communicate with 
the Chassis Manager. For example, Domain-1/User-1 will be checked against the corresponding 
domain’s authorization roles (Domain-1/AcsCmAdmin, Domain-1/AcsCmOperator, or Domain-
1/AcsCmUser). By default, a Chassis Manager administrator has privileges that are equal to the 
authorization role AcsCmAdmin. 
Table 45 lists the APIs and the corresponding authorized user roles. 
Table 45: Chassis manager APIs and corresponding authorized roles 
APIs AcsCmAdmin AcsCmOperator AcsCmUser 
Health/status information APIs 
GetChassisInfo X X X 
GetBladeInfo X X X 
GetAllBladesInfo X X X 
GetVersion X X X 
Blade management APIs 
GetBladeHealth X X X 
SetBladeAttentionLEDOn X X  
SetAllBladesAttentionLEDOn X X  
SetBladeAttentionLEDOff X X  
SetAllBladesAttentionLEDOff X X  
SetBladeDefaultPowerStateOn X X  
SetAllBladesDefaultPowerStateOn X X  



 
62 October 30, 2014 
 
APIs AcsCmAdmin AcsCmOperator AcsCmUser 
SetBladeDefaultPowerStateOff X X  
SetAllBladesDefaultPowerStateOff X X  
GetBladeDefaultPowerState X X X 
GetAllBladesDefaultPowerState X X X 
GetPowerState X X X 
GetAllPowerState X X X 
SetPowerOn X   
SetAllPowerOn X   
SetPowerOff X   
SetAllPowerOff X   
GetBladeState X X X 
GetAllBladesState X X X 
SetBladeOn X   
SetAllBladesOn X   
SetBladeOff X   
SetAllBladesOff X   
SetBladeActivePowerCycle X   
SetAllBladesActivePowerCycle X   
ReadBladeLog X X X 
ReadBladeLogWithTimeStamp X X X 
ClearBladelog X X  
GetBladePowerReading X X X 
GetAllBladesPowerReading X X X 
GetBladePowerLimit X X X 
GetAllBladesPowerLimit X X X 
SetBladePowerLimit X X  
SetAllBladesPowerLimit X X  
SetBladePowerLimitOn X X  
SetAllBladesPowerLimitOn X X  
SetBladePowerLimitOff X X  
SetAllBladesPowerLimitOff X X  



Open Compute Project  Open CloudServer OCS Chassis Management 
http://opencompute.org 63 
 
APIs AcsCmAdmin AcsCmOperator AcsCmUser 
GetNextBoot X X X 
SetNextBoot X X X 
StartBladeSerialSession X   
SendBladeSerialData X   
ReceiveBladeSerialData X   
StopBladeSerialSession X   
Asset Management APIs 
GetChassisManagerAssetInfo X X X 
GetPDBAssetInfo X X X 
GetBladeAssetInfo X X X 
SetChassisManagerAssetInfo X X  
SetPDBAssetInfo X X  
SetBladeAssetInfo X X  
Serial console device APIs 
StartSerialPortConsole X X  
StopSerialPortConsole X X  
SendSerialPortData X X  
ReceiveSerialPortData X X  
Chassis management APIs 
SetChassisAttentionLEDOn X X  
SetChassisAttentionLEDOff X X  
GetChassisAttentionLEDStatus X X X 
ReadChassisLog X X X 
ClearChassisLog X X  
ReadChassisLogWithTimeStamp X X X 
GetChassisHealth X X X 
SetACSocketPowerStateOn X X  
SetACSocketPowerStateOff X X  
GetACSocketPowerState X X X 
GetChassisNetworkProperties X  X 
AddChassisControllerUser X   



 
64 October 30, 2014 
 
APIs AcsCmAdmin AcsCmOperator AcsCmUser 
ChangeChassisControllerUserPassword X   
ChangeChassisControllerUserRole X   
RemoveChassisControllerUser X   
PSU APIs 
ResetPsu X X  
UpdatePsuFirmware X   
GetPSUFirmwareStatus X X X 
6.5 REST API: Response and Completion Codes 
The Chassis Manager interface is based on REST to more easily interface with the machines. The 
sections that follow describe the Chassis Manager functionality and provide the corresponding APIs 
and descriptions. 
Each REST API call has the following information encapsulated in its return packet to provide high-
level response status information: 
 <byte>  
Completion code  
 <string>  
Status description (a textual description of the result) when completion code is anything other 
than success. 
 <int>  
API version 
Version number of the REST API  
Currently, this has value ‘1’; it will be updated upon future API or response packet structure 
changes. 
Note: The NoActiveSerialSession = 0xB2 // error is thrown for Stop/Send/Receive serial session 
commands for both the blade and the port console when there is no active serial session. If you see 
this error, use a startserialsession API to create an active session. 
6.6 REST API: Descriptions, Usage Scenarios, and Sample 
Responses 
The sections that follow provide information about the Chassis Manager REST APIs. 



Open Compute Project  Open CloudServer OCS Chassis Management 
http://opencompute.org 65 
 
6.6.1 Gets Information about Chassis 
ChassisInfoResponse GetChassisInfo(bool bladeInfo, bool psuInfo, bool chassisInfo) 
https://localhost:8000/GetChassisInfo?bladeinfo=true&psuInfo=true&chassisInfo=true 
Usage scenario:  
This API is used to get the status of chassis components including blades (for example, GUID and power 
status), power supplies (for example, power draw, status, and serial number), batteries (charge level, 
power output, fault status) and Chassis Manager (for example, MAC/IP address of the network 
interfaces, and version information). The power supply status is not available during a PSU firmware 
upgrade process. 
Input parameters: (If no parameters are specified, the command fetches result for all) 
 bladeInfo (shows information about blades , optional) 
 psuInfo (shows information about power supplies , optional) 
 chassisInfo (shows Chassis Manager information , optional) 
Sample response: 
<ChassisInfoResponse 
xmlns="http://schemas.datacontract.org/2004/07/Microsoft.GFS.WCS.Contracts
" xmlns:i="http://www.w3.org/2001/XMLSchema-instance"> 
  <CompletionCode>Success</CompletionCode>  
  <statusDescription></statusDescription> 
  <apiVersion>1</apiVersion> 
<chassisController> 
  <CompletionCode>Success</CompletionCode> 
  <statusDescription></statusDescription>  
  <apiVersion>1</apiVersion> 
  <assetTag />  
  <firmwareVersion />  
  <hardwareVersion>0</hardwareVersion>  
- <networkProperties> 
- <ChassisNetworkPropertiesResponse> 
  <completionCode>Success</completionCode> 
  <statusDescription></statusDescription>  
  <apiVersion>1</apiVersion> 
  <ipAddress i:nil="true" />  
  <macAddress>08:9E:01:18:0C:07</macAddress>  
  <dhcpEnabled>false</dhcpEnabled>  
  <dhcpServer i:nil="true" />  
  <dnsAddress i:nil="true" />  
  <dnsDomain i:nil="true" />  



 
66 October 30, 2014 
 
  <dnsHostName i:nil="true" />  
  <gatewayAddress i:nil="true" />  
  <subnetMask i:nil="true" />  
  </ChassisNetworkPropertiesResponse> 
- <ChassisNetworkPropertiesResponse> 
  <completionCode>Success</completionCode>  
  <statusDescription></statusDescription> 
  <apiVersion>1</apiVersion> 
  <ipAddress>192.168.100.59</ipAddress>  
  <macAddress>08:9E:01:18:0C:08</macAddress>  
  <dhcpEnabled>true</dhcpEnabled>  
  <dhcpServer>192.168.100.8</dhcpServer>  
  <dnsAddress i:nil="true" />  
  <dnsDomain>wcs.lab</dnsDomain>  
  <dnsHostName>DVTCM03</dnsHostName>  
  <gatewayAddress i:nil="true" />  
  <subnetMask>255.255.255.0</subnetMask>  
  </ChassisNetworkPropertiesResponse> 
  </networkProperties> 
  <serialNumber />  
  <systemUptime>00:00:41.4301650</systemUptime>  
  </chassisController> 
<psuCollections> 
<PsuInfo> 
  <CompletionCode>Success</CompletionCode> 
  <statusDescription></statusDescription>  
  <apiVersion>1</apiVersion> 
  <id>1</id>  
  <powerOut>1011</powerOut>  
  <serialNumber>46-49-51-44-31-32-32-32-30-30-30-31-33-32</serialNumber>  
  <state>ON</state>  
  </PsuInfo> 
<PsuInfo> 
  <CompletionCode>Success</CompletionCode>  
  <statusDescription></statusDescription> 
  <apiVersion>1</apiVersion> 
  <id>2</id>  
  <powerOut>960</powerOut>  
  <serialNumber>46-49-51-44-31-32-32-32-30-30-30-31-30-35</serialNumber>  



Open Compute Project  Open CloudServer OCS Chassis Management 
http://opencompute.org 67 
 
  <state>ON</state>  
  </PsuInfo> 
... 
<PsuInfo> 
  <CompletionCode>Success</CompletionCode>  
  <statusDescription></statusDescription> 
  <apiVersion>1</apiVersion> 
  <id>6</id>  
  <powerOut>925</powerOut>  
  <serialNumber>46-49-51-44-31-32-32-32-30-30-30-31-30-37</serialNumber>  
  <state>ON</state>  
  </PsuInfo> 
  </psuCollections> 
 
<bladeCollections> 
<BladeInfo> 
  <CompletionCode>Success</CompletionCode> 
  <statusDescription></statusDescription>  
  <apiVersion>1</apiVersion> 
  <bladeGuid>ffffffff-ffff-ffff-ffff-ffffffffffff</bladeGuid>  
  <bladeName>BLADE1</bladeName>  
  <bladeMacAddress>Not Applicable</bladeMacAddress>  
  <id>1</id>  
  <powerState>ON</powerState>  
  </BladeInfo> 
<BladeInfo> 
  <CompletionCode>Success</CompletionCode>  
  <statusDescription></statusDescription> 
  <apiVersion>1</apiVersion> 
  <bladeGuid>ffffffff-ffff-ffff-ffff-ffffffffffff</bladeGuid>  
  <bladeName>BLADE2</bladeName>  
  <bladeMacAddress>Not Applicable</bladeMacAddress>  
  <id>2</id>  
  <powerState>ON</powerState>  
  </BladeInfo> 
... 
<BladeInfo> 
  <CompletionCode>Success</CompletionCode>  
  <statusDescription></statusDescription> 
  <apiVersion>1</apiVersion> 



 
68 October 30, 2014 
 
  <bladeGuid>ffffffff-ffff-ffff-ffff-ffffffffffff</bladeGuid>  
  <bladeName>BLADE24</bladeName>  
  <bladeMacAddress>Not Applicable</bladeMacAddress>  
  <id>24</id>  
  <powerState>ON</powerState>  
  </BladeInfo> 
  </bladeCollections> 
  
  </ChassisInfoResponse> 
6.6.2 Gets Information about Blade 
BladeInfoResponse  GetBladeInfo(int bladeId) 
https://localhost:8000/GetBladeInfo?bladeid=1 
Usage scenario:  
This API is used to get information about the blade (for example serial number and version information).   
Input parameters: 
 bladeId (blade index 1-48) 
Sample response:  
<BladeInfoResponse 
xmlns="http://schemas.datacontract.org/2004/07/Microsoft.GFS.WCS.Contracts
" xmlns:i="http://www.w3.org/2001/XMLSchema-instance"> 
 <bladeResponse> 
  <CompletionCode>Success</CompletionCode>  
  <statusDescription></statusDescription> 
  <apiVersion>1</apiVersion> 
  <bladeNumber>1</bladeNumber>  
  </bladeResponse> 
 <detailedBladeInfo> 
  <alertEnabled>true</alertEnabled>  
  <assetTag> Will be added </assetTag>  
 <bladeBmc> 
  <gateway>Not applicable</gateway>  
  <guid>4647ff2b-cb75-4ad6-85de-c612c5abdf87</guid>  
  <ipAddress>Not applicable</ipAddress>  
  <ipmiVersion>Not applicable</ipmiVersion>  
  <macAddress>Not applicable</macAddress>  
  <netmask>Not applicable</netmask>  



Open Compute Project  Open CloudServer OCS Chassis Management 
http://opencompute.org 69 
 
  <solEnabled>true</solEnabled>  
  <vlanTag>1</vlanTag>  
  </bladeBmc> 
  <dhcp>false</dhcp>  
  <firmwareVersion>01.03</firmwareVersion>  
  <hardwareVersion>T6M</hardwareVersion>  
  <id>1</id>  
  <ipAddress>0.0.0.0</ipAddress>  
  <ipmiEnabled>true</ipmiEnabled>  
  <logEnabled>true</logEnabled>  
  <macAddress>00-00-00-00-00-00</macAddress>  
  <numberComputeNodes>1</numberComputeNodes>  
  <serialNumber>MH822400349</serialNumber>  
  </detailedBladeInfo> 
  </BladeInfoResponse> 
6.6.3 Gets Information about All Blades 
GetAllBladesInfoResponse  GetAllBladesInfo() 
https://localhost:8000/GetAllBladesInfo? 
Usage scenario: 
This API is used to get information about all blades (for example serial numbers and version 
information). 
Input parameters: 
 bladeId  (blade index 1-48) 
Sample response:  
<GetAllBladesInfoResponse 
xmlns="http://schemas.datacontract.org/2004/07/Microsoft.GFS.WCS.Contracts
" xmlns:i="http://www.w3.org/2001/XMLSchema-instance"> 
 <BladeInfoResponse> 
 <bladeResponse> 
  <CompletionCode>Success</CompletionCode>  
  <statusDescription></statusDescription> 
  <apiVersion>1</apiVersion> 
  <bladeNumber>1</bladeNumber>  
  </bladeResponse> 
 <detailedBladeInfo> 
  <alertEnabled>true</alertEnabled>  
  <assetTag>Will be added</assetTag>  



 
70 October 30, 2014 
 
 <bladeBmc> 
  <gateway>Not applicable</gateway>  
  <guid>b560b268-c9e0-46da-8029-5f8d2eeed61e</guid>  
  <ipAddress>Not applicable</ipAddress>  
  <ipmiVersion>Not applicable</ipmiVersion>  
  <macAddress>Not applicable</macAddress>  
  <netmask>Not applicable</netmask>  
  <solEnabled>true</solEnabled>  
  <vlanTag>1</vlanTag>  
  </bladeBmc> 
  <dhcp>false</dhcp>  
  <firmwareVersion>01.03</firmwareVersion>  
  <hardwareVersion>T6M</hardwareVersion>  
  <id>1</id>  
  <ipAddress>0.0.0.0</ipAddress>  
  <ipmiEnabled>true</ipmiEnabled>  
  <logEnabled>true</logEnabled>  
  <macAddress>00-00-00-00-00-00</macAddress>  
  <numberComputeNodes>1</numberComputeNodes>  
  <serialNumber>MH822400349</serialNumber>  
  </detailedBladeInfo> 
  </BladeInfoResponse> 
... 
 <BladeInfoResponse> 
 <bladeResponse> 
  <CompletionCode>Success</CompletionCode>  
  <statusDescription></statusDescription> 
  <apiVersion>1</apiVersion> 
  <bladeNumber>24</bladeNumber>  
  </bladeResponse> 
 <detailedBladeInfo> 
  <alertEnabled>true</alertEnabled>  
  <assetTag>Blank For Now, need to locate in FRU</assetTag>  
 <bladeBmc> 
  <gateway>Not applicable</gateway>  
  <guid>c7954895-cb36-4a79-a5b3-8fa2fbb0795a</guid>  
  <ipAddress>Not applicable</ipAddress>  
  <ipmiVersion>Not applicable</ipmiVersion>  
  <macAddress>Not applicable</macAddress>  



Open Compute Project  Open CloudServer OCS Chassis Management 
http://opencompute.org 71 
 
  <netmask>Not applicable</netmask>  
  <solEnabled>true</solEnabled>  
  <vlanTag>1</vlanTag>  
  </bladeBmc> 
  <dhcp>false</dhcp>  
  <firmwareVersion>01.03</firmwareVersion>  
  <hardwareVersion>T6M</hardwareVersion>  
  <id>24</id>  
  <ipAddress>0.0.0.0</ipAddress>  
  <ipmiEnabled>true</ipmiEnabled>  
  <logEnabled>true</logEnabled>  
  <macAddress>00-00-00-00-00-00</macAddress>  
  <numberComputeNodes>1</numberComputeNodes>  
  <serialNumber>MH822400334</serialNumber>  
  </detailedBladeInfo> 
  </BladeInfoResponse> 
  </GetAllBladesInfoResponse> 
6.6.4 Turns Chassis Attention LED ON 
ChassisResponse   SetChassisAttentionLEDOn() 
https://localhost:8000/SetChassisAttentionLEDOn? 
Usage scenario:  
This API is used to turn the chassis attention LED ON. 
The attention LED indicates that the Chassis Manager needs attention. It directs service technicians to 
the correct chassis for repair. Chassis Manager logs are available through the management system to 
direct repair (through the ReadChassisLog() API). Users can also flag a service requirement by turning ON 
the attention LED. When possible, repairs will also be self-directed by the chassis management system. 
Operators/users must make sure that the chassis attention LED is turned OFF after service is complete. 
Input parameters: 
 None 
Sample response: 
<ChassisResponse 
xmlns="http://schemas.datacontract.org/2004/07/Microsoft.GFS.WCS.Contracts
" xmlns:i="http://www.w3.org/2001/XMLSchema-instance"> 
  <completionCode>Success</completionCode>  
  <statusDescription></statusDescription> 
  <apiVersion>1</apiVersion> 
  </ChassisResponse> 



 
72 October 30, 2014 
 
6.6.5 Turns Chassis Attention LED OFF 
ChassisResponse SetChassisAttentionLEDOff() 
https://localhost:8000/SetChassisAttentionLEDOff? 
Usage scenario:  
This API is used to turn the chassis attention LED OFF. 
The attention LED indicates that the Chassis Manager needs attention. It directs service technicians to 
the correct chassis for repair. Chassis Manager logs are available through the management system to 
direct repair (through the ReadChassisLog() API). Users can also flag a service requirement by turning ON 
the attention LED. When possible, repairs will also be self-directed by the chassis management system. 
Operators/users must make sure that the chassis attention LED is turned OFF after service is complete. 
Input parameters: 
 None 
Sample response: 
<ChassisResponse 
xmlns="http://schemas.datacontract.org/2004/07/Microsoft.GFS.WCS.Contracts
" xmlns:i="http://www.w3.org/2001/XMLSchema-instance"> 
  <completionCode>Success</completionCode>  
  <statusDescription></statusDescription> 
  <apiVersion>1</apiVersion> 
  </ChassisResponse> 
6.6.6 Gets Chassis Attention LED Status 
LEDStatusResponse  GetChassisAttentionLEDStatus() 
https://localhost:8000/GetChassisAttentionLEDStatus? 
Usage scenario:  
This API gets the chassis attention LED status (whether ON or OFF). 
The attention LED indicates that the Chassis Manager needs attention. It directs service technicians to 
the correct chassis for repair. Chassis Manager logs are available through the management system to 
direct repair (through the ReadChassisLog() API). Users can also flag a service requirement by turning ON 
the attention LED. When possible, repairs will also be self-directed by the chassis management system. 
Operators/users must make sure that the chassis attention LED is turned OFF after service is complete. 
Input parameters: 
 None 
Sample response: 
<LEDStatusResponse 
xmlns="http://schemas.datacontract.org/2004/07/Microsoft.GFS.WCS.Contracts



Open Compute Project  Open CloudServer OCS Chassis Management 
http://opencompute.org 73 
 
" xmlns:i="http://www.w3.org/2001/XMLSchema-instance"> 
  <completionCode>Success</completionCode>  
  <statusDescription></statusDescription> 
  <apiVersion>1</apiVersion> 
  <ledState>OFF</ledState>  
  </LEDStatusResponse> 
6.6.7 Turns Blade Attention LED ON 
BladeResponse SetBladeAttentionLEDOn(int bladeId) 
https://localhost:8000/SetBladeAttentionLEDOn?bladeId=1 
Usage scenario:  
This API turns the blade attention LED ON. 
The attention LED indicates that the blade needs attention. It directs service technicians to the correct 
blade for repair. Blade logs are available through the management system to direct repair (through the 
ReadBladeLog() API). Users can also flag a service requirement by turning ON the attention LED. 
Operators/users must make sure that the blade attention LED is turned OFF after service is complete. 
Input parameters: 
 bladeId (blade index 1-48) 
Sample response: 
<BladeResponse 
xmlns="http://schemas.datacontract.org/2004/07/Microsoft.GFS.WCS.Contracts
" xmlns:i="http://www.w3.org/2001/XMLSchema-instance"> 
  <CompletionCode>Success</CompletionCode>  
  <statusDescription></statusDescription> 
  <apiVersion>1</apiVersion> 
  <bladeNumber>1</bladeNumber>  
  </BladeResponse> 
6.6.8 Turns All Blade Attention LEDs ON 
AllBladesResponse SetAllBladesAttentionLEDOn() 
https://localhost:8000/SetAllBladesAttentionLEDOn? 
Usage scenario:  
This API turns the attention LEDs on all blades ON. 
The attention LED indicates that the blade needs attention. It directs service technicians to the correct 
blade for repair. Blade logs are available through the management system to direct repair (through the 
ReadBladeLog() API). Users can also flag a service requirement by turning ON the attention LED. 



 
74 October 30, 2014 
 
Operators/users must make sure that the blade attention LED is turned OFF after service is complete. 
Note that when multiple users are actively trying to access/modify the same state of a single blade or of 
different blades, ordering is not guaranteed. 
Input parameters: 
 None 
Sample response: 
- <AllBladesResponse 
xmlns="http://schemas.datacontract.org/2004/07/Microsoft.GFS.WCS.Contracts
" xmlns:i="http://www.w3.org/2001/XMLSchema-instance"> 
- <BladeResponse> 
  <CompletionCode>Success</CompletionCode>  
  <statusDescription></statusDescription> 
  <apiVersion>1</apiVersion> 
  <bladeNumber>1</bladeNumber>  
  </BladeResponse> 
- <BladeResponse> 
  <CompletionCode>Success</CompletionCode>  
  <statusDescription></statusDescription> 
  <apiVersion>1</apiVersion> 
  <bladeNumber>2</bladeNumber>  
  </BladeResponse> 
… 
- <BladeResponse> 
  <CompletionCode>Success</CompletionCode>  
  <statusDescription></statusDescription> 
  <apiVersion>1</apiVersion> 
  <bladeNumber>24</bladeNumber>  
  </BladeResponse> 
  </AllBladesResponse> 
6.6.9 Turns Blade Attention LED OFF 
BladeResponse SetBladeAttentionLEDOff(int bladeId) 
https://localhost:8000/SetBladeAttentionLEDOff?bladeId=1 
Usage scenario:  
This API turns the blade attention LED OFF. 
The attention LED indicates that the blade needs attention. It directs service technicians to the correct 
blade for repair. Blade logs are available through the management system to direct repair (through the 



Open Compute Project  Open CloudServer OCS Chassis Management 
http://opencompute.org 75 
 
ReadBladeLog() API). Users can also flag a service requirement by turning ON the attention LED. 
Operators/users must make sure that the blade attention LED is turned OFF after service is complete. 
Input parameters: 
 bladeId (blade index 1-48) 
Sample response: 
<BladeResponse 
xmlns="http://schemas.datacontract.org/2004/07/Microsoft.GFS.WCS.Contracts
" xmlns:i="http://www.w3.org/2001/XMLSchema-instance"> 
  <CompletionCode>Success</CompletionCode>  
  <statusDescription></statusDescription> 
  <apiVersion>1</apiVersion> 
  <bladeNumber>1</bladeNumber>  
  </BladeResponse> 
6.6.10 Turns All Blade Attention LEDs OFF 
AllBladesResponse SetAllBladesAttentionLEDOff() 
https://localhost:8000/SetAllBladesAttentionLEDOff? 
Usage scenario:  
This API is used to turn the attention LED on all blades OFF. 
The attention LED indicates that the blade needs attention. It directs service technicians to the correct 
blade for repair. Blade logs are available through the management system to direct repair (through the 
ReadBladeLog() API). Users can also flag a service requirement by turning ON the attention LED. 
Operators/users must make sure that the blade attention LED is turned OFF after service is complete. 
Note that when multiple users are actively trying to access/modify the same state of a single blade or of 
different blades, ordering is not guaranteed. 
Input parameters: 
 None 
Sample response: 
- <AllBladesResponse 
xmlns="http://schemas.datacontract.org/2004/07/Microsoft.GFS.WCS.Contracts
" xmlns:i="http://www.w3.org/2001/XMLSchema-instance"> 
- <BladeResponse> 
  <CompletionCode>Success</CompletionCode>  
  <statusDescription></statusDescription> 
  <apiVersion>1</apiVersion> 
  <bladeNumber>1</bladeNumber>  
  </BladeResponse> 



 
76 October 30, 2014 
 
- <BladeResponse> 
  <CompletionCode>Success</CompletionCode> 
  <statusDescription></statusDescription>  
  <apiVersion>1</apiVersion> 
  <bladeNumber>2</bladeNumber>  
  </BladeResponse> 
… 
- <BladeResponse> 
  <CompletionCode>Success</CompletionCode>  
  <statusDescription></statusDescription> 
  <apiVersion>1</apiVersion> 
  <bladeNumber>24</bladeNumber>  
  </BladeResponse> 
  </AllBladesResponse> 
6.6.11 Sets Default Blade Power State ON 
BladeResponse SetBladeDefaultPowerStateOn(int bladeId) 
https://localhost:8000/SetBladeDefaultPowerStateOn?bladeId=1 
Usage scenario:  
This API sets the default power state of a blade ON. 
The default power state of the blade is the state of the blade after it receives AC power, either when a 
blade is initially inserted in the slot or when power returns after a utility failure. If the default state is set 
to OFF, the blade will not be powered ON after receiving AC input power, and an explicit 
SetBladeActivePowerOn() API will need to be sent to power ON the blade. Note that the blade default 
power state does not affect the active power state of the blade, only their behavior after a power 
recycle. 
Input parameters: 
 bladeId (blade index 1-48) 
Sample response: 
<BladeResponse 
xmlns="http://schemas.datacontract.org/2004/07/Microsoft.GFS.WCS.Contracts
" xmlns:i="http://www.w3.org/2001/XMLSchema-instance"> 
  <CompletionCode>Success</CompletionCode>  
  <statusDescription></statusDescription> 
  <apiVersion>1</apiVersion> 
  <bladeNumber>1</bladeNumber>  
  </BladeResponse> 



Open Compute Project  Open CloudServer OCS Chassis Management 
http://opencompute.org 77 
 
6.6.12 Sets Default Power State of All Blades ON 
AllBladesResponse SetAllBladesDefaultPowerStateOn() 
https://localhost:8000/SetAllBladesDefaultPowerStateOn? 
Usage scenario:  
This API sets the default power state of all blades ON. 
The default power state of the blade is the state of the blade after it receives AC power, either when a 
blade is initially inserted in the slot or when power returns after a utility failure. If the default state is set 
to OFF, the blade will not be powered ON after receiving AC input power, and an explicit 
SetBladeActivePowerOn() API will need to be sent to power ON the blade. Note that the blade default 
power state does not affect the active power state of the blade; the default power state only affects 
their behavior after a power recycle. 
Note that when multiple users are actively trying to access/modify the same state of a single blade or of 
different blades, ordering is not guaranteed. 
Input parameters: 
 None 
Sample response: 
- <AllBladesResponse 
xmlns="http://schemas.datacontract.org/2004/07/Microsoft.GFS.WCS.Contracts
" xmlns:i="http://www.w3.org/2001/XMLSchema-instance"> 
- <BladeResponse> 
  <CompletionCode>Success</CompletionCode>  
  <statusDescription></statusDescription> 
  <apiVersion>1</apiVersion> 
  <bladeNumber>1</bladeNumber>  
  </BladeResponse> 
- <BladeResponse> 
  <CompletionCode>Success</CompletionCode> 
  <statusDescription></statusDescription>  
  <apiVersion>1</apiVersion> 
  <bladeNumber>2</bladeNumber>  
  </BladeResponse> 
... 
- <BladeResponse> 
  <CompletionCode>Success</CompletionCode>  
  <statusDescription></statusDescription> 
  <apiVersion>1</apiVersion> 
  <bladeNumber>24</bladeNumber>  



 
78 October 30, 2014 
 
  </BladeResponse> 
  </AllBladesResponse> 
6.6.13 Sets Default Blade Power State OFF 
BladeResponse SetBladeDefaultPowerStateOff(int bladeId) 
http://localhost:8000/SetBladeDefaultPowerStateOff?bladeId=1 
Usage scenario:  
This API sets the default power state of a blade OFF. 
The default power state of the blade is the state of the blade after it receives AC power, either when a 
blade is initially inserted in the slot or when power returns after a utility failure. If the default state is set 
to OFF, the blade will not be powered ON after receiving AC input power, and an explicit 
SetBladeActivePowerOn() API will need to be sent to power ON the blade. Note that the blade default 
power state does not affect the active power state of the blade; the default power state of a blade only 
affects the behavior after a power recycle. 
Input parameters: 
 bladeId (blade index 1-48) 
Sample response: 
<BladeResponse 
xmlns="http://schemas.datacontract.org/2004/07/Microsoft.GFS.WCS.Contracts
" xmlns:i="http://www.w3.org/2001/XMLSchema-instance"> 
  <completionCode>Success</completionCode>  
  <statusDescription></statusDescription> 
  <apiVersion>1</apiVersion> 
  <bladeNumber>1</bladeNumber>  
  </BladeResponse> 



Open Compute Project  Open CloudServer OCS Chassis Management 
http://opencompute.org 79 
 
6.6.14 Sets Default Power State of All Blades OFF 
AllBladesResponse SetAllBladesDefaultPowerStateOff() 
http://localhost:8000/SetAllBladesDefaultPowerStateOff?bladeId=1 
Sets the default power state of all blades OFF 
Usage scenario:  
This API sets the default power state of all blades OFF. 
The default power state of the blade is the state of the blade after it receives AC power, either when a 
blade is initially inserted in the slot or when power returns after a utility failure. If the default state is set 
to OFF, the blade will not be powered ON after receiving AC input power, and an explicit 
SetBladeActivePowerOn() API will need to be sent to power ON the blade. Note that the blade default 
power state does not affect the active power state of the blade; the default power state only affects the 
behavior after a power recycle. 
Note also that when multiple users are actively trying to access/modify the same state of a single blade 
or of different blades, ordering is not guaranteed. 
Input parameters: 
 None 
Sample response: 
- <AllBladesResponse 
xmlns="http://schemas.datacontract.org/2004/07/Microsoft.GFS.WCS.Contracts
" xmlns:i="http://www.w3.org/2001/XMLSchema-instance"> 
- <BladeResponse> 
  <completionCode>Success</completionCode>  
  <statusDescription></statusDescription> 
  <apiVersion>1</apiVersion> 
  <bladeNumber>1</bladeNumber>  
  </BladeResponse> 
- <BladeResponse> 
  <completionCode>Success</completionCode>  
  <statusDescription></statusDescription> 
  <apiVersion>1</apiVersion> 
  <bladeNumber>2</bladeNumber>  
  </BladeResponse> 
... 
- <BladeResponse> 
  <completionCode>Success</completionCode>  
  <statusDescription></statusDescription> 
  <apiVersion>1</apiVersion> 



 
80 October 30, 2014 
 
  <bladeNumber>24</bladeNumber>  
  </BladeResponse> 
  </AllBladesResponse> 
6.6.15 Gets Default Blade Power State  
BladeStateResponse GetBladeDefaultPowerState(int bladeId) 
https://localhost:8000/GetBladeDefaultPowerState?bladeId=1 
Usage scenario:  
This API gets the default power state of the blade.  
The default power state of the blade is the state of the blade after it receives AC power, either when a 
blade is initially inserted in the slot or when power returns after a utility failure. If the default state is set 
to OFF, the blade will not be powered ON after receiving AC input power, and an explicit 
SetBladeActivePowerOn() API will need to be sent to power ON the blade. Note that the blade default 
power state does not affect the active power state of the blade; the default power state only affects the 
behavior after a power recycle. 
Input parameters: 
 bladeId (blade index 1-48) 
Sample response: 
BladeStateResponse 
xmlns="http://schemas.datacontract.org/2004/07/Microsoft.GFS.WCS.Contracts
" xmlns:i="http://www.w3.org/2001/XMLSchema-instance"> 
- <bladeResponse> 
  <completionCode>Success</completionCode>  
  <statusDescription></statusDescription> 
  <apiVersion>1</apiVersion> 
  <bladeNumber<  
>1</bladeNumber>  
  </bladeResponse> 
  <bladeState>ON</bladeState>  
  </BladeStateResponse> 
6.6.16 Gets the Default Power State of All Blades 
GetAllBladesStateResponse GetAllBladesDefaultPowerState() 
https://localhost:8000/GetAllBladesDefaultPowerState? 
Usage scenario:  
The default power state of the blade is the state of the blade after it receives AC power, either when a 
blade is initially inserted in the slot or when power returns after a utility failure. If the default state is set 



Open Compute Project  Open CloudServer OCS Chassis Management 
http://opencompute.org 81 
 
to OFF, the blade will not be powered ON after receiving AC input power, and an explicit 
SetBladeActivePowerOn() API will need to be sent to power ON the blade. Note that the blade default 
power state does not affect the active power state of the blade; the default power state only affects the 
behavior after a power recycle. 
Note also that when multiple users are actively trying to access/modify the same state of a single blade 
or of different blades, ordering is not guaranteed. 
Input parameters: 
 None 
Sample response: 
- <GetAllBladesStateResponse 
xmlns="http://schemas.datacontract.org/2004/07/Microsoft.GFS.WCS.Contracts
" xmlns:i="http://www.w3.org/2001/XMLSchema-instance"> 
- <BladeStateResponse> 
- <bladeResponse> 
  <completionCode>Success</completionCode>  
  <statusDescription></statusDescription> 
  <apiVersion>1</apiVersion> 
  <bladeNumber>1</bladeNumber>  
  </bladeResponse> 
  <bladeState>ON</bladeState>  
  </BladeStateResponse> 
- <BladeStateResponse> 
- <bladeResponse> 
  <completionCode>Success</completionCode>  
  <statusDescription></statusDescription> 
  <apiVersion>1</apiVersion> 
  <bladeNumber>2</bladeNumber>  
  </bladeResponse> 
  <bladeState>ON</bladeState>  
  </BladeStateResponse> 
... 
- <BladeStateResponse> 
- <bladeResponse> 
  <completionCode>Success</completionCode>  
  <statusDescription></statusDescription> 
  <apiVersion>1</apiVersion> 
  <bladeNumber>24</bladeNumber>  
  </bladeResponse> 
  <bladeState>ON</bladeState>  



 
82 October 30, 2014 
 
  </BladeStateResponse> 
  </GetAllBladesStateResponse> 
6.6.17 Gets Outlet Power State of Blade 
PowerStateResponse GetPowerState(int bladeId) 
https://localhost:8000/GetPowerState?bladeId=1 
Usage scenario:  
This API gets the AC outlet power state of a blade (whether or not the blade is receiving AC power).  
When ON, the blade is receiving AC power (hard-power state). When AC power is supplied to the blade 
and when the default power state of the blade is ON, the blade chipset will receive power and the boot 
process will be initiated. If the default power state of the blade is OFF when AC power is applied, the 
blade chipset will not receive power (and the boot process will not be initiated) unless an explicit 
“SetBladeOn” command is sent to the blade.  
When OFF, the blade is not receiving AC power 
Input parameters: 
 bladeId (blade index 1-48) 
Sample response: 
<PowerStateResponse 
xmlns="http://schemas.datacontract.org/2004/07/Microsoft.GFS.WCS.Contracts
" xmlns:i="http://www.w3.org/2001/XMLSchema-instance"> 
- <bladeResponse> 
  <completionCode>Success</completionCode>  
  <statusDescription></statusDescription> 
  <apiVersion>1</apiVersion> 
  <bladeNumber>1</bladeNumber>  
  </bladeResponse> 
  <powerState>ON</powerState>  
  </PowerStateResponse> 
6.6.18 Gets AC Outlet Power State of All Blades 
GetAllPowerStateResponse GetAllPowerState() 
https://localhost:8000/GetAllPowerState?  
Usage scenario:  
This API gets the AC outlet power state of all blades (whether or not the blades are receiving AC power). 
When ON, the blade is receiving AC power (hard-power state). When AC power is supplied to the blade 
and when the default power state of the blade is ON, the blade chipset will receive power and the boot 



Open Compute Project  Open CloudServer OCS Chassis Management 
http://opencompute.org 83 
 
process will be initiated. If the default power state of the blade is OFF when AC power is applied, the 
blade chipset will not receive power (and the boot process will not be initiated) unless an explicit 
“SetBladeOn” command is sent to the blade.  
When OFF, the blade is not receiving AC power. 
Note that when multiple users are actively trying to access/modify the same state of a single blade or of 
different blades, ordering is not guaranteed. 
Input parameters: 
 None 
Sample response: 
- < GetAllPowerStateResponse 
xmlns="http://schemas.datacontract.org/2004/07/Microsoft.GFS.WCS.Contracts
" xmlns:i="http://www.w3.org/2001/XMLSchema-instance"> 
- <PowerStateResponse> 
- <bladeResponse> 
  <completionCode>Success</completionCode>  
  <statusDescription></statusDescription> 
  <apiVersion>1</apiVersion> 
  <bladeNumber>1</bladeNumber>  
  </bladeResponse> 
  <powerState>ON</powerState>  
  </PowerStateResponse> 
- <PowerStateResponse> 
- <bladeResponse> 
  <completionCode>Success</completionCode>  
  <statusDescription></statusDescription> 
  <apiVersion>1</apiVersion> 
  <bladeNumber>2</bladeNumber>  
  </bladeResponse> 
  <powerState>ON</powerState>  
  </PowerStateResponse> 
... 
- <PowerStateResponse> 
- <bladeResponse> 
  <completionCode>Success</completionCode>  
  <statusDescription></statusDescription> 
  <apiVersion>1</apiVersion> 
  <bladeNumber>24</bladeNumber>  
  </bladeResponse> 
  <powerState>ON</powerState>  



 
84 October 30, 2014 
 
  </PowerStateResponse> 
  </ GetAllPowerStateResponse> 
6.6.19 Turns AC Outlet Power ON for Blade 
BladeResponse SetPowerOn(int bladeId) 
https://localhost:8000/SetPowerOn?bladeId=1 
Usage scenario:  
This API turns the AC power outlet power ON for a blade. 
When ON, the blade is receiving AC power (hard-power state). When AC power is supplied to the blade 
and when the default power state of the blade is ON, the blade chipset will receive power and the boot 
process will be initiated. If the default power state of the blade is OFF when AC power is applied, the 
blade chipset will not receive power (and the boot process will not be initiated) unless an explicit 
“SetBladeOn” command is sent to the blade.  
When OFF, the blade is not receiving AC power. 
Note: it would take up to 50 seconds for the BMC to start responding to commands after a setpoweron 
– AC cycling. 
Input parameters: 
 bladeId (blade index 1-48) 
Sample response: 
<BladeResponse 
xmlns="http://schemas.datacontract.org/2004/07/Microsoft.GFS.WCS.Contracts
" xmlns:i="http://www.w3.org/2001/XMLSchema-instance"> 
  <completionCode>Success</completionCode>  
  <statusDescription></statusDescription> 
  <apiVersion>1</apiVersion> 
  <bladeNumber>1</bladeNumber>  
  </BladeResponse> 
6.6.20 Turns the AC Outlet Power ON for All Blades 
AllBladesResponse SetAllPowerOn() 
https://localhost:8000/SetAllPowerOn?  
Usage scenario:  
This API turns the AC power outlet ON for all blades. 
When ON, the blade is receiving AC power (hard-power state). When AC power is supplied to the blade 
and when the default power state of the blade is ON, the blade chipset will receive power and the boot 



Open Compute Project  Open CloudServer OCS Chassis Management 
http://opencompute.org 85 
 
process will be initiated. If the default power state of the blade is OFF when AC power is applied, the 
blade chipset will not receive power (and the boot process will not be initiated) unless an explicit 
“SetBladeOn” command is sent to the blade.  
When OFF, the blade is not receiving AC power. 
Note that when multiple users are actively trying to access/modify the same state of a single blade or of 
different blades, ordering is not guaranteed. It would take up to 50 seconds for the BMC to start 
responding to commands after a setpoweron – AC cycling. 
Input parameters: 
 None 
Sample response: 
- <AllBladesResponse 
xmlns="http://schemas.datacontract.org/2004/07/Microsoft.GFS.WCS.Contracts
" xmlns:i="http://www.w3.org/2001/XMLSchema-instance"> 
- <BladeResponse> 
  <completionCode>Success</completionCode>  
  <statusDescription></statusDescription> 
  <apiVersion>1</apiVersion> 
  <bladeNumber>1</bladeNumber>  
  </BladeResponse> 
- <BladeResponse> 
  <completionCode>Success</completionCode>  
  <statusDescription></statusDescription> 
  <apiVersion>1</apiVersion> 
  <bladeNumber>2</bladeNumber>  
  </BladeResponse> 
... 
- <BladeResponse> 
  <completionCode>Success</completionCode>  
  <statusDescription></statusDescription> 
  <apiVersion>1</apiVersion> 
  <bladeNumber>24</bladeNumber>  
  </BladeResponse> 
  </AllBladesResponse> 
6.6.21 Turns AC Outlet Power OFF for Blade 
BladeResponse SetPowerOff(int bladeId) 
https://localhost:8000/SetPowerOff?bladeId=1 
Usage scenario:  



 
86 October 30, 2014 
 
This API turns the AC power OFF for a blade. 
When ON, the blade is receiving AC power (hard-power state). When AC power is supplied to the blade 
and when the default power state of the blade is ON, the blade chipset will receive power and the boot 
process will be initiated. If the default power state of the blade is OFF when AC power is applied, the 
blade chipset will not receive power (and the boot process will not be initiated) unless an explicit 
“SetBladeOn” command is sent to the blade.  
When OFF, the blade is not receiving AC power. 
Note: it would take up to 50 seconds for the BMC to start responding to commands after a setpoweroff 
– AC cycling. 
Input parameters: 
 bladeId (blade index 1-48) 
Sample response: 
<BladeResponse 
xmlns="http://schemas.datacontract.org/2004/07/Microsoft.GFS.WCS.Contracts
" xmlns:i="http://www.w3.org/2001/XMLSchema-instance"> 
  <completionCode>Success</completionCode>  
  <statusDescription></statusDescription> 
  <apiVersion>1</apiVersion> 
  <bladeNumber>1</bladeNumber>  
  </BladeResponse> 
6.6.22 Turns AC Outlet Power OFF for All Blades 
AllBladesResponse SetAllPowerOff() 
https://localhost:8000/SetAllPowerOff?  
Usage scenario:  
This API turns the AC power OFF for all blades. 
When ON, the blade is receiving AC power (hard-power state). When AC power is supplied to the blade 
and when the default power state of the blade is ON, the blade chipset will receive power and the boot 
process will be initiated. If the default power state of the blade is OFF when AC power is applied, the 
blade chipset will not receive power (and the boot process will not be initiated) unless an explicit 
“SetBladeOn” command is sent to the blade.  
When OFF, the blade is not receiving AC power. 
Note that when multiple users are actively trying to access/modify the same state of a single blade or of 
different blades, ordering is not guaranteed. It would take up to 50 seconds for the BMC to start 
responding to commands after a setpoweroff – AC cycling. 
Input parameters: 



Open Compute Project  Open CloudServer OCS Chassis Management 
http://opencompute.org 87 
 
 None 
Sample response: 
- <AllBladesResponse 
xmlns="http://schemas.datacontract.org/2004/07/Microsoft.GFS.WCS.Contracts
" xmlns:i="http://www.w3.org/2001/XMLSchema-instance"> 
  <completionCode>Success</completionCode>  
  <statusDescription></statusDescription> 
  <apiVersion>1</apiVersion> 
- <BladeResponse> 
  <completionCode>Success</completionCode>  
  <statusDescription></statusDescription> 
  <apiVersion>1</apiVersion> 
  <bladeNumber>1</bladeNumber>  
  </BladeResponse> 
- <BladeResponse> 
  <completionCode>Success</completionCode>  
  <statusDescription></statusDescription> 
  <apiVersion>1</apiVersion> 
  <bladeNumber>2</bladeNumber>  
  </BladeResponse> 
... 
- <BladeResponse> 
  <completionCode>Success</completionCode>  
  <statusDescription></statusDescription> 
  <apiVersion>1</apiVersion> 
  <bladeNumber>24</bladeNumber>  
  </BladeResponse> 
  </AllBladesResponse> 
6.6.23 Gets the ON/OFF State of Blade 
BladeState GetBladeState(int bladeId) 
https://localhost:8000/GetBladeState?bladeId=1 
Usage scenario:  
This API is used to get the ON/OFF state of a blade (whether or not blade chipset is receiving power). 
When ON, the blade is receiving AC power (hard-power state) and the chipset is receiving power (soft-
power state).  
When OFF, the blade chipset is not receiving power. 



 
88 October 30, 2014 
 
Input parameters: 
 bladeId (blade index 1-48) 
Sample response: 
<BladeStateResponse 
xmlns="http://schemas.datacontract.org/2004/07/Microsoft.GFS.WCS.Contracts
" xmlns:i="http://www.w3.org/2001/XMLSchema-instance"> 
- <bladeResponse> 
  <completionCode>Success</completionCode>  
  <statusDescription></statusDescription> 
  <apiVersion>1</apiVersion> 
  <bladeNumber>1</bladeNumber>  
  </bladeResponse> 
  <powerState>ON</powerState>  
  </BladeStateResponse> 
6.6.24 Gets the ON/OFF State of All Blades 
GetAllBladesStateResponse GetAllBladesState() 
https://localhost:8000/GetAllBladesState?  
Usage scenario:  
This API gets the ON/OFF state of all blades (whether or not blade chipsets are receiving power). 
When ON, the blades are receiving AC power (hard-power state) and the chipsets are receiving power 
(soft-power state).  
When OFF, the blade chipsets are not receiving power. 
Note that when multiple users are actively trying to access/modify the same state of a single blade or of 
different blades, ordering is not guaranteed. 
Input parameters: 
 None 
Sample response: 
- <GetAllBladesStateResponse 
xmlns="http://schemas.datacontract.org/2004/07/Microsoft.GFS.WCS.Contracts
" xmlns:i="http://www.w3.org/2001/XMLSchema-instance"> 
  <completionCode>Success</completionCode>  
  <statusDescription></statusDescription> 
  <apiVersion>1</apiVersion> 
- <BladeStateResponse> 
- <bladeResponse> 



Open Compute Project  Open CloudServer OCS Chassis Management 
http://opencompute.org 89 
 
  <completionCode>Success</completionCode>  
  <statusDescription></statusDescription> 
  <apiVersion>1</apiVersion> 
  <bladeNumber>1</bladeNumber>  
  </bladeResponse> 
  <powerState>ON</powerState>  
  </BladeStateResponse> 
- <BladeStateResponse> 
- <bladeResponse> 
  <completionCode>Success</completionCode>  
  <statusDescription></statusDescription> 
  <apiVersion>1</apiVersion> 
  <bladeNumber>2</bladeNumber>  
  </bladeResponse> 
  <powerState>ON</powerState>  
  </BladeStateResponse> 
... 
- <BladeStateResponse> 
- <bladeResponse> 
  <completionCode>Success</completionCode>  
  <statusDescription></statusDescription> 
  <apiVersion>1</apiVersion> 
  <bladeNumber>24</bladeNumber>  
  </bladeResponse> 
  <powerState>ON</powerState>  
  </BladeStateResponse> 
  </GetAllBladesStateResponse> 
6.6.25 Supplies Power to the Blade Chipset 
BladeResponse SetBladeOn(int bladeId) 
https://localhost:8000/SetBladeOn?bladeId=1 
Usage scenario:  
This API is used to supply power to the blade chipset (initialize the boot process). 
When ON, the blade is receiving AC power (hard-power state) and the chipset is receiving power (soft-
power state).  
When OFF, the blade chipset is not receiving power. 
Input parameters: 



 
90 October 30, 2014 
 
 bladeId (blade index 1-48) 
Sample response: 
<BladeResponse 
xmlns="http://schemas.datacontract.org/2004/07/Microsoft.GFS.WCS.Contracts
" xmlns:i="http://www.w3.org/2001/XMLSchema-instance"> 
  <completionCode>Success</completionCode>  
  <statusDescription></statusDescription> 
  <apiVersion>1</apiVersion> 
  <bladeNumber>1</bladeNumber>  
  </BladeResponse> 
6.6.26 Supplies Power to All Blade Chipsets 
AllBladesResponse SetAllBladesOn() 
https://localhost:8000/SetAllBladesOn?  
Usage scenario:  
This API is used to supply power to the chipsets (initialize the boot process). 
When ON, the blades are receiving AC power (hard-power state) and the chipsets are receiving power 
(soft-power state).  
When OFF, the blade chipsets are not receiving power. 
Note that when multiple users are actively trying to access/modify the same state of a single blade or of 
different blades, ordering is not guaranteed. 
Input parameters: 
 None 
Sample response: 
- <AllBladesResponse 
xmlns="http://schemas.datacontract.org/2004/07/Microsoft.GFS.WCS.Contracts
" xmlns:i="http://www.w3.org/2001/XMLSchema-instance"> 
  <completionCode>Success</completionCode>  
  <statusDescription></statusDescription> 
  <apiVersion>1</apiVersion> 
- <BladeResponse> 
  <completionCode>Success</completionCode>  
  <statusDescription></statusDescription> 
  <apiVersion>1</apiVersion> 
  <bladeNumber>1</bladeNumber>  
  </BladeResponse> 



Open Compute Project  Open CloudServer OCS Chassis Management 
http://opencompute.org 91 
 
- <BladeResponse> 
  <completionCode>Success</completionCode>  
  <statusDescription></statusDescription> 
  <apiVersion>1</apiVersion> 
  <bladeNumber>2</bladeNumber>  
  </BladeResponse> 
... 
- <BladeResponse> 
  <completionCode>Success</completionCode>  
  <statusDescription></statusDescription> 
  <apiVersion>1</apiVersion> 
  <bladeNumber>24</bladeNumber>  
  </BladeResponse> 
  </AllBladesResponse> 
6.6.27 Stops Power to Blade Chipset 
BladeResponse SetBladeOff(int bladeId) 
https://localhost:8000/SetBladeOff?bladeId=1 
Usage scenario:  
This API is used to remove or stop power to the chipset. 
When ON, the blade is receiving AC power (hard-power state) and the chipset is receiving power (soft-
power state).  
When OFF, the blade chipset is not receiving power. 
Input parameters: 
 bladeId (blade index 1-48) 
Sample response: 
<BladeResponse 
xmlns="http://schemas.datacontract.org/2004/07/Microsoft.GFS.WCS.Contracts
" xmlns:i="http://www.w3.org/2001/XMLSchema-instance"> 
  <completionCode>Success</completionCode>  
  <statusDescription></statusDescription> 
  <apiVersion>1</apiVersion> 
  <bladeNumber>1</bladeNumber>  
  </BladeResponse> 
6.6.28 Stops Power to All Blade Chipsets 



 
92 October 30, 2014 
 
AllBladesResponse SetAllBladesOff() 
https://localhost:8000/SetAllBladesOff?  
Usage scenario:  
This API is used to remove or turn OFF power to the chipsets. 
When ON, the blades are receiving AC power (hard-power state) and the chipsets are receiving power 
(soft-power state).  
When OFF, the blade chipsets are not receiving power. 
Note that when multiple users are actively trying to access/modify the same state of a single blade or of 
different blades, ordering is not guaranteed. 
Input parameters: 
 None 
Sample response: 
- <AllBladesResponse 
xmlns="http://schemas.datacontract.org/2004/07/Microsoft.GFS.WCS.Contracts
" xmlns:i="http://www.w3.org/2001/XMLSchema-instance"> 
  <completionCode>Success</completionCode>  
  <statusDescription></statusDescription> 
  <apiVersion>1</apiVersion> 
- <BladeResponse> 
  <completionCode>Success</completionCode>  
  <statusDescription></statusDescription> 
  <apiVersion>1</apiVersion> 
  <bladeNumber>1</bladeNumber>  
  </BladeResponse> 
- <BladeResponse> 
  <completionCode>Success</completionCode>  
  <statusDescription></statusDescription> 
  <apiVersion>1</apiVersion> 
  <bladeNumber>2</bladeNumber>  
  </BladeResponse> 
... 
- <BladeResponse> 
  <completionCode>Success</completionCode>  
  <statusDescription></statusDescription> 
  <apiVersion>1</apiVersion> 
  <bladeNumber>24</bladeNumber>  
  </BladeResponse> 



Open Compute Project  Open CloudServer OCS Chassis Management 
http://opencompute.org 93 
 
  </AllBladesResponse> 
6.6.29 Power Cycle Blade 
BladeResponse SetBladeActivePowerCycle(int bladeId, uint offTime) 
https://localhost:8000/SetBladeActivePowerCycle?bladeId=1&offTime=0 
Usage scenario:  
This API is used to power cycle (or soft reset) a blade. 
Power cycle resets the blade (causing a software reboot sequence).  The blade AC power signal remains 
ON throughout the process. Any serial session active on that blade will continue to be active during this 
process.  
Input parameters: 
 bladeId (blade index 1-48) 
 offTime (time interval [in seconds] when the blade is powered off; if not specified, the default 
interval is 0 [optional]) 
Sample response: 
<BladeResponse 
xmlns="http://schemas.datacontract.org/2004/07/Microsoft.GFS.WCS.Contracts
" xmlns:i="http://www.w3.org/2001/XMLSchema-instance"> 
  <completionCode>Success</completionCode>  
  <statusDescription></statusDescription> 
  <apiVersion>1</apiVersion> 
  <bladeNumber>1</bladeNumber>  
  </BladeResponse> 
6.6.30 Power Cycle All Blades 
AllBladesResponse SetAllBladesActivePowerCycle(uint offTime) 
https://localhost:8000/SetAllBladesActivePowerCycle?offTime=0  
Usage scenario:  
This API power cycles (or soft resets) all blades. 
Power cycle resets the blade (causing a software reboot sequence).  The blade AC power signal remains 
ON throughout the process. Any serial session active on that blade will continue to be active during this 
process.  
Note that when multiple users are actively trying to access/modify the same state of a single blade or of 
different blades, ordering is not guaranteed. 
Input parameters: 
 offTime (time interval [in seconds] when the blade is powered off; if not specified, the 



 
94 October 30, 2014 
 
default interval is 0 [optional]) 
Sample response: 
- <AllBladesResponse 
xmlns="http://schemas.datacontract.org/2004/07/Microsoft.GFS.WCS.Contracts
" xmlns:i="http://www.w3.org/2001/XMLSchema-instance"> 
  <completionCode>Success</completionCode>  
  <statusDescription></statusDescription> 
  <apiVersion>1</apiVersion> 
- <BladeResponse> 
  <completionCode>Success</completionCode>  
  <statusDescription></statusDescription> 
  <apiVersion>1</apiVersion> 
  <bladeNumber>1</bladeNumber>  
  </BladeResponse> 
- <BladeResponse> 
  <completionCode>Success</completionCode>  
  <statusDescription></statusDescription> 
  <apiVersion>1</apiVersion> 
  <bladeNumber>2</bladeNumber>  
  </BladeResponse> 
... 
- <BladeResponse> 
  <completionCode>Success</completionCode>  
  <statusDescription></statusDescription> 
  <apiVersion>1</apiVersion> 
  <bladeNumber>24</bladeNumber>  
  </BladeResponse> 
  </AllBladesResponse> 
6.6.31 Turns Chassis AC Sockets (TOR Switches) ON 
ChassisResponse SetACSocketPowerStateOn(uint portNo) 
https://localhost:8000/SetACSocketPowerStateOn?portNo=1 
Usage scenario:  
This API turns the chassis AC sockets (TOR switches) ON. 
The AC socket power state refers to the active power state of the COM ports (and therefore to the 
power state of the device connected to the port) on the Chassis Manager. For example, the TOR switch 
is connected to COM1 (port number 1). 



Open Compute Project  Open CloudServer OCS Chassis Management 
http://opencompute.org 95 
 
Power ON/OFF APIs for the AC sockets makes it possible to remotely power-reset the device The power 
ON/OFF APIs are also used for enabling/disabling.  
Input parameters: 
 portNo (port number of the AC socket) 
Sample response: 
<ChassisResponse 
xmlns="http://schemas.datacontract.org/2004/07/Microsoft.GFS.WCS.Contracts
" xmlns:i="http://www.w3.org/2001/XMLSchema-instance"> 
  <completionCode>Success</completionCode>  
  <statusDescription></statusDescription> 
  <apiVersion>1</apiVersion> 
  </ChassisResponse> 
6.6.32 Turns Chassis AC Sockets (TOR Switches) OFF 
ChassisResponse SetACSocketPowerStateOff(uint portNo) 
https://localhost:8000/SetACSocketPowerStateOff?portNo=2 
Usage scenario:  
This API turns the chassis AC sockets (TOR switches) OFF. 
The AC socket power state refers to the active power state of the COM ports (and therefore to the 
power state of the device connected to the port) on the Chassis Manager. For example, the TOR switch 
is connected to COM1 (port number 1). 
Power ON/OFF APIs for the AC sockets makes it possible to remotely power-reset the device The power 
ON/OFF APIs are also used for enabling/disabling.  
Input parameters: 
 portNo (port number of the AC socket) 
Sample response: 
<ChassisResponse 
xmlns="http://schemas.datacontract.org/2004/07/Microsoft.GFS.WCS.Contracts
" xmlns:i="http://www.w3.org/2001/XMLSchema-instance"> 
  <completionCode>Success</completionCode>  
  <statusDescription></statusDescription> 
  <apiVersion>1</apiVersion> 
  </ChassisResponse> 
6.6.33 Gets Status of Chassis AC Sockets (TOR Switches)  
ACSocketStateResponse GetACSocketPowerState(uint portNo) 



 
96 October 30, 2014 
 
https://localhost:8000/GetACSocketPowerState?portNo=1 
Usage scenario:  
This API gets the status of the chassis AC sockets (TOR switches).  
The AC socket power state refers to the active power state of the COM ports (and therefore to the 
power state of the device connected to the port) on the Chassis Manager. For example, the TOR switch 
is connected to COM1 (port number 1). 
Power ON/OFF APIs for the AC sockets makes it possible to remotely power-reset the device The power 
ON/OFF APIs are also used for enabling/disabling.  
Input parameters: 
 portNo (port number of the AC socket) 
Sample response: 
<ACSocketStateResponse 
xmlns="http://schemas.datacontract.org/2004/07/Microsoft.GFS.WCS.Contracts
" xmlns:i="http://www.w3.org/2001/XMLSchema-instance"> 
  <completionCode>Success</completionCode>  
  <statusDescription></statusDescription> 
  <apiVersion>1</apiVersion> 
  <portNo>1</portNo>  
  <powerState>ON</powerState>  
  </ACSocketStateResponse> 
6.6.34 Starts Serial Session to Blade 
StartSerialResponse StartBladeSerialSession(int bladeId) 
https://localhost:8000/StartBladeSerialSessions?bladeId=1 
Usage scenario:  
This API starts a serial session to a blade. 
Users might want to open a serial session to a blade to debug, to view blade boot messages, or to 
execute BIOS commands. A provided VT100 console client continuously polls the blade for serial session 
data (using the ReceiveBladeSerialData API). Any user command entered using the VT100 console is sent 
to the blade (using the SendBladeSerialData API). 
Note that this session might close unexpectedly if there are any simultaneous IPMI commands issued to 
any of the chassis blades or if the session is inactive (no SendBladeSerialData request from client) for 
more than five minutes.  
Input parameters: 
 bladeId (blade index 1-48) 
Sample response: 



Open Compute Project  Open CloudServer OCS Chassis Management 
http://opencompute.org 97 
 
StartSerialResponse.sessionToken: 11234 
StartSerialResponse.CompletionCode: success 
6.6.35 Stop Serial Session to Blade 
ChassisResponse  StopBladeSerialSession(int bladeId, string sessionToken, bool forceKill=false)  
https://localhost:8000/StopBladeSerialSessions?bladeId=1 
Usage scenario:  
This API stops a serial session to a blade. 
Users might want to open a serial session to a blade to debug, to view blade boot messages, or to 
execute BIOS commands. A provided VT100 console client continuously polls the blade for serial session 
data (using the ReceiveBladeSerialData API). Any user command entered using the VT100 console is sent 
to the blade (using the SendBladeSerialData API). 
Note that this session might close unexpectedly if there are any simultaneous IPMI commands issued to 
any of the chassis blades (when the config. parameter forceKill is set to true) or if the session is inactive 
(no SendBladeSerialData request from client) for more than five minutes.  However, when forceKill is set 
to false, an already existing blade serial console session will not be interrupted, and an incoming IPMI 
command will be ignored. 
Input parameters: 
 bladeId (blade index 1-48) 
 sessionToken (generated as part of the StartBladeSerialSession API) 
 forceKill (true or false with semantics explained above) 
Sample response:   
  <completionCode>Success</completionCode>  
  <statusDescription></statusDescription> 
 
6.6.36 Sends Data to Blade Serial Device 
ChassisResponse SendBladeSerialData(int bladeId, string sessionToken, byte[] data) 
https://localhost:8000/SendBladeSerialData?bladeId=1?sessionToken? 
Usage scenario:  
This API sends the data entered by user on the serial console to the blade serial device (internal API used 
by the serial-client-proxy) 
Users might want to open a serial session to a blade to debug, to view blade boot messages, or to 
execute BIOS commands. A provided VT100 console client continuously polls the blade for serial session 
data (using the ReceiveBladeSerialData API). Any user command entered using the VT100 console is sent 
to the blade (using the SendBladeSerialData API). 
Note that this session might close unexpectedly if there are any simultaneous IPMI commands issued to 



 
98 October 30, 2014 
 
any of the chassis blades or if the session is inactive (no SendBladeSerialData request from client) for 
more than five minutes.  
 Input parameters: 
 bladeId (blade index 1-48) 
 sessionToken (generated as part of the StartBladeSerialSession API) 
 data (data to be sent) 
Sample response: 
ChassisResponse .completionCode: Success 
6.6.37 Receives Data from Blade 
SerialDataResponse ReceiveBladeSerialData(int bladeId, string sessionToken) 
https://localhost:8000/ReceiveBladeSerialData?bladeId=1?sessionToken? 
Usage scenario:  
This API receives data from the blade (internal API used by the serial-client-proxy). 
Users might want to open a serial session to a blade to debug, to view blade boot messages, or to 
execute BIOS commands. A provided VT100 console client continuously polls the blade for serial session 
data (using the ReceiveBladeSerialData API). Any user command entered using the VT100 console is sent 
to the blade (using the SendBladeSerialData API). 
Note that this session might close unexpectedly if there are any simultaneous IPMI commands issued to 
any of the chassis blades or if the session is inactive (no SendBladeSerialData request from client) for 
more than five minutes.  
Input parameters: 
 bladeId (blade index 1-48) 
 sessionToken (token id generated as part of the StartBladeSerialSession API) 
Sample response: 
SerialDataResponse .bladeResponse.bladeCompletionCode: Success 
SerialDataResponse .data 
6.6.38 Starts Serial Port Console 
StartSerialResponse StartSerialPortConsole(int portId, int sessionTimeoutInSecs, int 
deviceTimeoutInMsecs); 
https://localhost:8000/StartSerialPortConsole?PorId=3 
Usage scenario:  
This API is used to open a serial-port console terminal to serial devices that are connected to 
the Chassis Manager (for example, TOR network switches). Note that the serial console might 
close if session is inactive (no SendSerialPortData request from client) for more than two 



Open Compute Project  Open CloudServer OCS Chassis Management 
http://opencompute.org 99 
 
minutes.  
A provided VT100 console client continuously polls the serial device for data (using the 
ReceiveSerialPortData API). Any user command entered using the VT100 console is sent to the device 
(using the SendSerialPortData API). 
Input parameters: 
 portId (com1-com2) 
 SessionTimeoutInSecs(Optional) 
 DeviceTimeoutInMsecs(Optional) 
Sample response: 
StartSerialResponse.sessionToken: 32656 
StartSerialResponse.CompletionCode: success 
6.6.39 Stops Serial Port Console 
ChassisResponse StopSerialPortConsole(int portId, string sessionToken, bool forceKill); 
https://localhost:8000/StopSerialPortConsole?PorId=1 
Usage scenario:  
This API is used to close a serial-port console terminal to serial devices that are connected to 
the Chassis Manager (for example, TOR network switches). Note that the serial console might 
close if session is inactive (no SendSerialPortData request from client) for more than two 
minutes.  
A provided VT100 console client continuously polls the serial device for data (using the 
ReceiveSerialPortData API). Any user command entered using the VT100 console is sent to the device 
(using the SendSerialPortData API). 
ForceKill option when set to true will kill all existing sessions to the port. 
Input parameters: 
 portId (com1-com2) 
 sessionToken 
 forceKill 
Sample response: 
ChassisResponse.CompletionCode: success 
6.6.40 Sends Serial Port Data 
ChassisResponse SendSerialPortData(string portId, string sessionToken, byte[] data) 
https://localhost:8000/SendSerialPortData?portId=1?sessionToken? 
Sends the serial data to the blade 



 
100 October 30, 2014 
 
Usage scenario: 
This is an internal API used for sending data from the user serial-client terminal to serial devices 
connected to the Chassis Manager (for example, user commands executed on the TOR network switch 
serial console). Note that the serial console might close if session is inactive(no SendSerialPortData 
request from client) for more than two minutes. 
A provided VT100 console client continuously polls the serial device for data (using the 
ReceiveSerialPortData API). Any user command entered using the VT100 console is sent to the device 
(using the SendSerialPortData API). 
Input parameters:  
 portId (com1-com2) 
 sessionToken (token id) 
 data (data to be sent) 
Sample response: 
ChassisResponse.CompletionCode: Success 
6.6.41 Receives Serial Port Data 
SerialDataResponse ReceiveSerialPortData(string portId, string sessionToken) 
https://localhost:8000/ReceiveSerialPortData?portId=1?sessionToken? 
Usage scenario: 
This is an internal API used for receiving data on the terminal from serial devices connected to the 
Chassis Manager (for example, user commands executed on the TOR network switch serial console). 
Note that the serial console might close if session is inactive(no SendSerialPortData request from 
client) for more than two minutes. 
A provided VT100 console client continuously polls the serial device for data (using the 
ReceiveSerialPortData API). Any user command entered using the VT100 console is sent to the device 
(using the SendSerialPortData API). 
Input parameters:  
 portId (com1-com2) 
 sessionToken  (token id) 
Sample response: 
ChassisResponse.CompletionCode: Success 
SerialData.data 
6.6.42 Reads the Chassis Log (with timestamp parameter) 
LogResponse ReadChassisLog() 
LogResponse ReadChassisLogWithTimestamp(Datetime startTimestamp, Datetime endTimestamp) 



Open Compute Project  Open CloudServer OCS Chassis Management 
http://opencompute.org 101 
 
https://localhost:8000/ReadChassisLog? 
Usage scenario: 
This API reads the chassis log. 
The chassis log contains information about the various alerts and warning messages associated 
with devices connected to the Chassis Manager (for example, blades overheating, and fan/PSU 
failure). The chassis log also contains user audit information, such as timestamp/activity 
performed by the user. 
Input parameters:  
 startTimestamp (read log from the start timestamp, optional) 
 endTimestamp (read log till the given end timestamp, optional) 
Sample response: 
- <ChassisLogResponse 
xmlns="http://schemas.datacontract.org/2004/07/Microsoft.GFS.WCS.Contracts
" xmlns:i="http://www.w3.org/2001/XMLSchema-instance"> 
  <completionCode>Success</completionCode>  
  <statusDescription></statusDescription> 
  <apiVersion>1</apiVersion> 
- <logEntries> 
- <LogEntry> 
  <eventDescription><user>,Invoked </eventDescription>  
  <eventTime>2012-09-11T21:04:33.024</eventTime>  
  </LogEntry> 
- <LogEntry> 
  <eventDescription><user>,Invoked </eventDescription>  
  <eventTime>2012-09-11T21:04:33.117</eventTime>  
  </LogEntry> 
... 
- <LogEntry> 
  <eventDescription><user>,Invoked 
ReadChassisLog()</eventDescription>  
  <eventTime>2012-09-11T21:20:03.366</eventTime>  
  </LogEntry> 
  </logEntries> 
  </ChassisLogResponse> 
6.6.43 Clears the Chassis Log 
ClearResponse ClearChassisLog() 
https://localhost:8000/ClearChassisLog? 
Usage scenario: 



 
102 October 30, 2014 
 
This API clears the chassis log. Users must periodically clear the consumed log entries because 
there are size restrictions on the Chassis Manager storage space. 
 
Input parameters:  
 None 
Sample response: 
<ChassisResponse 
xmlns="http://schemas.datacontract.org/2004/07/Microsoft.GFS.WCS.Contracts
" xmlns:i="http://www.w3.org/2001/XMLSchema-instance"> 
  <completionCode>Success</completionCode>  
  <statusDescription></statusDescription> 
  <apiVersion>1</apiVersion> 
  </ChassisResponse> 
6.6.44 Reads Log from Blade (with timestamp parameter) 
LogResponse ReadBladeLog(int bladeId) 
LogResponse ReadBladeLogWithTimestamp(int bladeId, uint logType, Datetime startTimestamp, 
Datetime endTimestamp) 
https://localhost:8000/ReadBladeLog?bladeId=1 
Usage scenario: 
This API reads the log of a blade. Blade logs (system event logs) contain information about 
events, warning, and alerts pertaining to that blade (for example, thermal throttling of blades 
because of overheating). 
Input parameters:  
 bladeId (blade index, 1-48) 
 startTimestamp (read log from this given start timestamp, optional) 
 endTimestamp (read log till the given end timestamp, optional) 
Sample response: 
- <ChassisLogResponse 
xmlns="http://schemas.datacontract.org/2004/07/Microsoft.GFS.WCS.Contracts
" xmlns:i="http://www.w3.org/2001/XMLSchema-instance"> 
  <completionCode>Failure</completionCode>  
  <statusDescription>The CM did not respond</statusDescription> 
  <apiVersion>1</apiVersion> 
- <logEntries> 
- <LogEntry> 
  
<eventDescription>Sensor_SpecificDrive_Slot2433328Assertion111</eventDescr
iption>  



Open Compute Project  Open CloudServer OCS Chassis Management 
http://opencompute.org 103 
 
  <eventTime>2012-08-23T14:35:21</eventTime>  
  </LogEntry> 
- <LogEntry> 
  
<eventDescription>Sensor_SpecificDrive_Slot2443328Assertion111</eventDescr
iption>  
  <eventTime>2012-08-23T14:35:21</eventTime>  
  </LogEntry> 
... 
- <LogEntry> 
  <eventDescription>DiscreteTemperature187257Desertion3</eventDescription>  
  <eventTime>2012-08-23T16:11:08</eventTime>  
  </LogEntry> 
  </logEntries> 
  </ChassisLogResponse> 
6.6.45 Clears Log from Blade 
BladeResponse ClearBladelog(int bladeId) 
https://localhost:8000/ClearBladeLog?bladeId=1 
Usage scenario: 
This API clears the log from a blade. 
Blade logs (system event logs) contain information about events, warning, and alerts pertaining to that 
blade (for example, thermal throttling of blades because of overheating). 
Input parameters:  
 bladeId  (blade index, 1-48) 
Sample response: 
- <BladeResponse 
xmlns="http://schemas.datacontract.org/2004/07/Microsoft.GFS.WCS.Contracts
" xmlns:i="http://www.w3.org/2001/XMLSchema-instance"> 
  <completionCode>Success</completionCode>  
  <statusDescription></statusDescription> 
  <apiVersion>1</apiVersion> 
  <bladeNumber>1</bladeNumber>  
  </BladeResponse> 
6.6.46 Gets Power Reading from Blade 
BladePowerReadingResponse  GetBladePowerReading(int bladeId) 
https://localhost:8000/GetBladePowerReading?bladeId=1 



 
104 October 30, 2014 
 
Usage scenario: 
This API is used to get the power reading of a blade. It can be used for monitoring or for other power-
control mechanisms (see the SetBladePowerLimit() API). 
Input parameters:  
 bladeId (blade index, 1-48) 
Sample response: 
- <BladePowerReadingResponse 
xmlns="http://schemas.datacontract.org/2004/07/Microsoft.GFS.WCS.Contracts
" xmlns:i="http://www.w3.org/2001/XMLSchema-instance"> 
  <completionCode>Success</completionCode>  
  <statusDescription></statusDescription> 
  <apiVersion>1</apiVersion> 
- <bladeResponse> 
  <completionCode>Success</completionCode>  
  <statusDescription></statusDescription> 
  <apiVersion>1</apiVersion> 
  <bladeNumber>1</bladeNumber>  
  </bladeResponse> 
  <powerReading>308</powerReading>  
  </BladePowerReadingResponse> 
6.6.47 Gets Power Readings from All Blades 
GetAllBladesPowerReadingResponse GetAllBladesPowerReading() 
https://localhost:8000/GetAllBladesPowerReading? 
Usage scenario: 
This API can be used for monitoring or for other power-control mechanisms (see the 
SetBladePowerLimit() API). 
Note that when multiple users are actively trying to access/modify the same state of a single blade or of 
different blades, ordering is not guaranteed. 
Input parameters:  
 None 
Sample response: 
- <GetAllBladesPowerReadingResponse 
xmlns="http://schemas.datacontract.org/2004/07/Microsoft.GFS.WCS.Contracts
" xmlns:i="http://www.w3.org/2001/XMLSchema-instance"> 
- <BladePowerReadingResponse> 
  <completionCode>Success</completionCode>  
  <statusDescription></statusDescription> 



Open Compute Project  Open CloudServer OCS Chassis Management 
http://opencompute.org 105 
 
  <apiVersion>1</apiVersion> 
- <bladeResponse> 
  <completionCode>Success</completionCode>  
  <statusDescription></statusDescription> 
  <apiVersion>1</apiVersion> 
  <bladeNumber>1</bladeNumber>  
  </bladeResponse> 
  <powerReading>308</powerReading>  
  </BladePowerReadingResponse> 
- <BladePowerReadingResponse> 
  <completionCode>Success</completionCode>  
  <statusDescription></statusDescription> 
  <apiVersion>1</apiVersion> 
- <bladeResponse> 
  <completionCode>Success</completionCode>  
  <statusDescription></statusDescription> 
  <apiVersion>1</apiVersion> 
  <bladeNumber>2</bladeNumber>  
  </bladeResponse> 
  <powerReading>311</powerReading>  
  </BladePowerReadingResponse> 
... 
- <BladePowerReadingResponse> 
  <completionCode>Success</completionCode>  
  <statusDescription></statusDescription> 
  <apiVersion>1</apiVersion> 
- <bladeResponse> 
  <completionCode>Success</completionCode>  
  <statusDescription></statusDescription> 
  <apiVersion>1</apiVersion> 
  <bladeNumber>24</bladeNumber>  
  </bladeResponse> 
  <powerReading>310</powerReading>  
  </BladePowerReadingResponse> 
  </GetAllBladesPowerReadingResponse> 
6.6.48 Gets Power Limit of Blade 
GetBladeLimitResponse GetBladePowerLimit(int bladeId) 
https://localhost:8000/GetBladePowerLimit?bladeId=1 
Usage scenario: 



 
106 October 30, 2014 
 
This API can be used to get the power limit that is set on a particular blade. 
Note: This API internally uses Intel ME for power limiting and reporting. Note that 
GetBladePowerLimit will fail with completion code 0x80 if there isn’t an active 
SetBladePowerLimit. So use GetBladePowerLimit after SetBladePowerLimit. 
 
Input parameters:  
 bladeId  (blade index, 1-48) 
Sample response: 
- <BladePowerLimitResponse 
xmlns="http://schemas.datacontract.org/2004/07/Microsoft.GFS.WCS.Contracts
" xmlns:i="http://www.w3.org/2001/XMLSchema-instance"> 
  <completionCode>Success</completionCode>  
  <statusDescription></statusDescription> 
  <apiVersion>1</apiVersion> 
- <bladeResponse> 
  <completionCode>Success</completionCode>  
  <statusDescription></statusDescription> 
  <apiVersion>1</apiVersion> 
  <bladeNumber>1</bladeNumber>  
  </bladeResponse> 
  <powerReading>750</powerReading>  
  </BladePowerLimitResponse> 
6.6.49 Gets Power Limit of All Blades 
GetAllBladesPowerLimitResponse GetAllBladesPowerLinit() 
https://localhost:8000/GetAllBladesPowerLimit? 
Usage scenario: 
This API can be used to get the power limit that is set on all blades in a chassis. 
Note: When multiple users are actively trying to access/modify the same state of a single blade or of 
different blades, ordering is not guaranteed. 
This API internally uses Intel ME for power limiting and reporting. Note that 
GetBladePowerLimit will fail with completion code 0x80 if there isn’t an active 
SetBladePowerLimit. So use GetBladePowerLimit after SetBladePowerLimit. 
Input parameters:  
 None 
Sample response: 



Open Compute Project  Open CloudServer OCS Chassis Management 
http://opencompute.org 107 
 
- <GetAllBladesPowerLimitResponse 
xmlns="http://schemas.datacontract.org/2004/07/Microsoft.GFS.WCS.Contracts
" xmlns:i="http://www.w3.org/2001/XMLSchema-instance"> 
- <BladePowerLimitResponse> 
  <completionCode>Success</completionCode>  
  <statusDescription></statusDescription> 
  <apiVersion>1</apiVersion> 
- <bladeResponse> 
  <completionCode>Success</completionCode>  
  <statusDescription></statusDescription> 
  <apiVersion>1</apiVersion> 
  <bladeNumber>1</bladeNumber>  
  </bladeResponse> 
  <powerReading>750</powerReading>  
  </BladePowerLimitResponse> 
- <BladePowerLimitResponse> 
  <completionCode>Success</completionCode>  
  <statusDescription></statusDescription> 
  <apiVersion>1</apiVersion> 
- <bladeResponse> 
  <completionCode>Success</completionCode>  
  <statusDescription></statusDescription> 
  <apiVersion>1</apiVersion> 
  <bladeNumber>2</bladeNumber>  
  </bladeResponse> 
  <powerReading>750</powerReading>  
  </BladePowerLimitResponse> 
... 
- <BladePowerLimitResponse> 
  <completionCode>Success</completionCode>  
  <statusDescription></statusDescription> 
  <apiVersion>1</apiVersion> 
- <bladeResponse> 
  <completionCode>Success</completionCode>  
  <statusDescription></statusDescription> 
  <apiVersion>1</apiVersion> 
  <bladeNumber>24</bladeNumber>  
  </bladeResponse> 
  <powerReading>750</powerReading>  
  </BladePowerLimitResponse> 
  </GetAllBladesPowerLmitResponse> 



 
108 October 30, 2014 
 
6.6.50 Sets Power Limit on Blade 
BladeResponse SetBladePowerLimit(int bladeId, double powerLimitInWatts) 
https://localhost:8000/SetBladePowerLimit?bladeId=1&powerLimitInWatts=750  
Usage scenario: 
This API is used to set the power limit for a blade; if the user wants to set the same power limit 
for all the blades, the SetAllBladesPowerLimit() API can be used. SetBladePowerLimitOn API has 
to be executed to actually realize the set power limit in the device. 
Power limits can be set for a variety of reasons, including energy savings and under-
provisioning (consolidating more servers under a power hierarchy). 
The min/max power limit is specified in app.config in the Chassis Manager. 
 
Input parameters:  
 bladeId (blade index 1-48 
 powerLimitInWatts  
Sample response: 
- <BladeResponse 
xmlns="http://schemas.datacontract.org/2004/07/Microsoft.GFS.WCS.Contracts
" xmlns:i="http://www.w3.org/2001/XMLSchema-instance"> 
  <completionCode>Success</completionCode>  
  <statusDescription></statusDescription> 
  <apiVersion>1</apiVersion> 
  <bladeNumber>1</bladeNumber>  
  </BladeResponse> 
6.6.51 Sets Power Limit on All Blades 
AllBladesResponse  SetAllBladesPowerLimit(double powerLimitInWatts) 
https://localhost:8000/SetAllBladesPowerLimit?powerLimitInWatts=750  
Usage scenario: 
This API is used to set the power limit for all blades in a chassis; if the user wants to set heterogeneous 
power limits, the SetBladePowerLimit() API can be used Power limits can be set for a variety of reasons, 
including energy savings and under-provisioning (consolidating more servers under a power hierarchy). 
SetBladePowerLimitOn API has to be executed to actually realize the set power limit in the device. 
Note that when multiple users are actively trying to access/modify the same state of a single blade or of 
different blades, ordering is not guaranteed. 
 
Input parameters:  
 powerLimitInWatts  



Open Compute Project  Open CloudServer OCS Chassis Management 
http://opencompute.org 109 
 
Sample response: 
- <AllBladesResponse 
xmlns="http://schemas.datacontract.org/2004/07/Microsoft.GFS.WCS.Contracts
" xmlns:i="http://www.w3.org/2001/XMLSchema-instance"> 
  <completionCode>Success</completionCode>  
  <statusDescription></statusDescription> 
  <apiVersion>1</apiVersion> 
- <BladeResponse> 
  <completionCode>Success</completionCode>  
  <statusDescription></statusDescription> 
  <apiVersion>1</apiVersion> 
  <bladeNumber>1</bladeNumber>  
  </BladeResponse> 
- <BladeResponse> 
  <completionCode>Success</completionCode>  
  <statusDescription></statusDescription> 
  <apiVersion>1</apiVersion> 
  <bladeNumber>2</bladeNumber>  
  </BladeResponse> 
... 
- <BladeResponse> 
  <completionCode>Success</completionCode>  
  <statusDescription></statusDescription> 
  <apiVersion>1</apiVersion> 
  <bladeNumber>24</bladeNumber>  
  </BladeResponse> 
  </AllBladesResponse> 
6.6.52 Activates Blade Power Limit 
BladeResponse SetBladePowerLimitOn(int bladeId) 
https://localhost:8000/SetBladePowerLimitOn?bladeId=1  
Usage scenario: 
This API activates the power limit for a blade and enables power throttling.  
Power limits can be set for a variety of reasons, including energy savings and under-provisioning 
(consolidating more servers under a power hierarchy). 
Input parameters:  
 bladeId (blade index 1-48 
Sample response: 
<BladeResponse 



 
110 October 30, 2014 
 
xmlns="http://schemas.datacontract.org/2004/07/Microsoft.GFS.WCS.Contracts
" xmlns:i="http://www.w3.org/2001/XMLSchema-instance"> 
  <completionCode>Success</completionCode>  
  <statusDescription></statusDescription> 
  <apiVersion>1</apiVersion> 
  <bladeNumber>1</bladeNumber>  
  </BladeResponse> 
6.6.53 Activates Power Limit on All Blades 
AllBladesResponse  SetAllBladesPowerLimitOn() 
https://localhost:8000/SetAllBladesPowerLimitOn?   
Usage scenario: 
This API activates the power limit for all blades in a chassis and enables power throttling. 
Power limits can be set for a variety of reasons, including energy savings and under-provisioning 
(consolidating more servers under a power hierarchy). 
Input parameters:  
 None 
Sample response: 
- <AllBladesResponse 
xmlns="http://schemas.datacontract.org/2004/07/Microsoft.GFS.WCS.Contracts
" xmlns:i="http://www.w3.org/2001/XMLSchema-instance"> 
  <completionCode>Success</completionCode>  
  <statusDescription></statusDescription> 
  <apiVersion>1</apiVersion> 
- <BladeResponse> 
  <completionCode>Success</completionCode>  
  <statusDescription></statusDescription> 
  <apiVersion>1</apiVersion> 
  <bladeNumber>1</bladeNumber>  
  </BladeResponse> 
- <BladeResponse> 
  <completionCode>Success</completionCode>  
  <statusDescription></statusDescription> 
  <apiVersion>1</apiVersion> 
  <bladeNumber>2</bladeNumber>  
  </BladeResponse> 
... 
- <BladeResponse> 



Open Compute Project  Open CloudServer OCS Chassis Management 
http://opencompute.org 111 
 
  <completionCode>Success</completionCode>  
  <statusDescription></statusDescription> 
  <apiVersion>1</apiVersion> 
  <bladeNumber>24</bladeNumber>  
  </BladeResponse> 
  </AllBladesResponse> 
6.6.54 Deactivates Blade Power Limit 
BladeResponse SetBladePowerLimitOff(int bladeId) 
https://localhost:8000/SetBladePowerLimitOff?bladeId=1  
Usage scenario: 
This API deactivates the power limit for a blade and disables power throttling. 
Power limits can be set for a variety of reasons, including energy savings and under-
provisioning (consolidating more servers under a power hierarchy). 
Input parameters:  
 bladeId (blade index 1-48) 
Sample response: 
<BladeResponse 
xmlns="http://schemas.datacontract.org/2004/07/Microsoft.GFS.WCS.Contracts
" xmlns:i="http://www.w3.org/2001/XMLSchema-instance"> 
  <completionCode>Success</completionCode>  
  <statusDescription></statusDescription> 
  <apiVersion>1</apiVersion> 
  <bladeNumber>1</bladeNumber>  
  </BladeResponse> 
6.6.55 Deactivates Power Limit on All Blades 
AllBladesResponse  SetAllBladesPowerLimitOff() 
https://localhost:8000/SetAllBladesPowerLimitOff?   
Usage scenario: 
This API deactivates the power limit for all blades in a chassis and disables power throttling. 
Power limits can be set for a variety of reasons, including energy savings and under-provisioning 
(consolidating more servers under a power hierarchy). 
Input parameters:  
 None 
Sample response: 



 
112 October 30, 2014 
 
- <AllBladesResponse 
xmlns="http://schemas.datacontract.org/2004/07/Microsoft.GFS.WCS.Contracts
" xmlns:i="http://www.w3.org/2001/XMLSchema-instance"> 
  <completionCode>Success</completionCode>  
  <statusDescription></statusDescription> 
  <apiVersion>1</apiVersion> 
- <BladeResponse> 
  <completionCode>Success</completionCode>  
  <statusDescription></statusDescription> 
  <apiVersion>1</apiVersion> 
  <bladeNumber>1</bladeNumber>  
  </BladeResponse> 
- <BladeResponse> 
  <completionCode>Success</completionCode>  
  <statusDescription></statusDescription> 
  <apiVersion>1</apiVersion> 
  <bladeNumber>2</bladeNumber>  
  </BladeResponse> 
... 
- <BladeResponse> 
  <completionCode>Success</completionCode>  
  <statusDescription></statusDescription> 
  <apiVersion>1</apiVersion> 
  <bladeNumber>24</bladeNumber>  
  </BladeResponse> 
  </AllBladesResponse> 
6.6.56 Gets Chassis Controller Network Properties 
ChassisNetworkPropertiesResponse GetChassisNetworkProperties() 
https://localhost:8000/GetChassisNetworkProperties?  
Usage scenario: 
This API gets the chassis controller network properties including MAC address, IP address, subnet mask, 
DHCP Enabled/Disabled. 
Note that Microsoft does not support setting network properties of the Chassis Manager and 
encourages users to use standard Windows interface/APIs for this. 
Input parameters:  
 None 
Sample response: 



Open Compute Project  Open CloudServer OCS Chassis Management 
http://opencompute.org 113 
 
- <ChassisNetworkPropertiesResponse 
xmlns="http://schemas.datacontract.org/2004/07/Microsoft.GFS.WCS.Contracts
" xmlns:i="http://www.w3.org/2001/XMLSchema-instance"> 
  <completionCode>Success</completionCode>  
  <statusDescription></statusDescription> 
  <apiVersion>1</apiVersion> 
- <ChassisNetworkProperty> 
<completionCode>Success</completionCode>  
  <statusDescription></statusDescription> 
  <apiVersion>1</apiVersion> 
  <ipAddress>192.168.100.59</ipAddress>  
  <macAddress>08:9E:01:18:0C:08</macAddress>  
  <dhcpEnabled>true</dhcpEnabled>  
  <dhcpServer>192.168.100.8</dhcpServer>  
  <dnsAddress i:nil="true" />  
  <dnsDomain>wcs.lab</dnsDomain>  
  <dnsHostName>DVTCM03</dnsHostName>  
  <gatewayAddress i:nil="true" />  
  <subnetMask>255.255.255.0</subnetMask>  
  </ChassisNetworkProperty> 
  </ChassisNetworkPropertiesResponse> 
6.6.57 Adds New Chassis Controller User 
ChassisResponse AddChassisControllerUser(string userName, string passwordString, WCSSecurityRole 
role) 
https://localhost:8000/AddChassisControllerUser?userName=xxx&passwordString=yyyy&role=1  
Usage scenario: 
This API is used to add a new chassis controller user with a specified password with privileges for 
accessing the Chassis Manager command line interface. The role parameter indicates the requested 
WCS user privilege level for this user (see below). 
    public enum WCSSecurityRole : int 
    { 
        // WCS Roles 
        WcsCmAdmin = 2, 
        WcsCmOperator = 1, 
        WcsCmUser = 0 
    } 
Input parameters:  
 userName – username associated with the user 
 passwordString 
Password for this user.  



 
114 October 30, 2014 
 
Password that do not adhere to standard windows user complexity requirements will result in 
API failure with appropriate error message thrown. 
 role 
Indicates the requested WCS user privilege level for this user. 
Sample response: 
<ChassisResponse 
xmlns="http://schemas.datacontract.org/2004/07/Microsoft.GFS.WCS.Contracts
" xmlns:i="http://www.w3.org/2001/XMLSchema-instance"> 
  <completionCode>Success</completionCode>  
  <statusDescription></statusDescription> 
  <apiVersion>1</apiVersion> 
  </ChassisResponse> 
6.6.58 Changes Password for Existing Chassis Controller User 
ChassisResponse ChangeChassisControllerUserPassword(string userName, string newPassword) 
https://localhost:8000/ChangeChassisControllerUserPassword?userName=xxx &newPassword=yyyy 
Usage scenario: 
Changes the username and password for an existing user in the chassis controller. 
Input parameters:  
 userName 
 newpassword 
Sample response: 
<ChassisResponse 
xmlns="http://schemas.datacontract.org/2004/07/Microsoft.GFS.WCS.Contracts
" xmlns:i="http://www.w3.org/2001/XMLSchema-instance"> 
  <completionCode>Success</completionCode>  
  <statusDescription></statusDescription> 
  <apiVersion>1</apiVersion> 
  </ChassisResponse> 
6.6.59 Changes Role for Existing Chassis Controller User 
ChassisResponse ChangeChassisControllerUserRole(string userName, WCSSecurityRole role) 
https://localhost:8000/ChangeChassisControllerUserRole?userName=xxx &role=1 
Usage scenario: 
This API is used to change the role associated with the user (see below). 
    public enum WCSSecurityRole : int 
    { 
        // WCS Roles 



Open Compute Project  Open CloudServer OCS Chassis Management 
http://opencompute.org 115 
 
        WcsCmAdmin = 2, 
        WcsCmOperator = 1, 
        WcsCmUser = 0 
    } 
Input parameters:  
 userName 
 role 
Sample response: 
<ChassisResponse 
xmlns="http://schemas.datacontract.org/2004/07/Microsoft.GFS.WCS.Contracts
" xmlns:i="http://www.w3.org/2001/XMLSchema-instance"> 
  <completionCode>Success</completionCode>  
  <statusDescription></statusDescription> 
  <apiVersion>1</apiVersion> 
  </ChassisResponse> 
6.6.60 Removes Existing Chassis Controller User 
ChassisResponse RemoveChassisControllerUser(string userName) 
https://localhost:8000/RemoveChassisControllerUser?userName=xxx  
Usage scenario: 
This command is used to remove an existing chassis controller user. 
Input parameters:  
userName 
Sample response: 
<ChassisResponse 
xmlns="http://schemas.datacontract.org/2004/07/Microsoft.GFS.WCS.Contracts
" xmlns:i="http://www.w3.org/2001/XMLSchema-instance"> 
  <completionCode>Success</completionCode>  
  <statusDescription></statusDescription> 
  <apiVersion>1</apiVersion> 
  </ChassisResponse> 
6.6.61 Get Health of Chassis 
ChassisHealthResponse GetChassisHealth(bool bladeHealth, bool psuHealth, bool fanHealth) 
https://localhost:8000/GetChassisHealth 
Usage scenario: 
This API can be used for status/health monitoring of chassis devices such as blade, psu, and fan. The 
power supply status is not available during a PSU firmware upgrade process. 



 
116 October 30, 2014 
 
 
The BladeType attribute specified as part of the BladeShellResponse refers to the type of blade, server 
(compute server), JBod (storage server) or unknown (device not reachable or not populated) . 
 
Input parameters: 
- bladeHealth 
- psuHealth 
- fanHealth 
- bladeHealth 
Note: If none of the parameters are specified, the API will fetch result for all components. 
Sample response: 
- <ChassisHealthResponse 
xmlns="http://schemas.datacontract.org/2004/07/Microsoft.GFS.WCS.Contracts" 
xmlns:i="http://www.w3.org/2001/XMLSchema-instance"> 
  <completionCode>Success</completionCode>  
  <statusDescription></statusDescription> 
  <apiVersion>1</apiVersion> 
- <bladeShellCollection> 
- <BladeShellResponse> 
  <completionCode>Success</completionCode>  
  <statusDescription></statusDescription> 
  <apiVersion>1</apiVersion> 
  <bladeId>1</bladeId>  
  <bladeState>ON</bladeState>  
  <bladeType>Server</bladeType>  
  </BladeShellResponse> 
- <BladeShellResponse> 
  <completionCode>Success</completionCode>  
  <statusDescription></statusDescription> 
  <apiVersion>1</apiVersion> 
  <bladeId>2</bladeId>  
  <bladeState>Healthy</bladeState>  
  <bladeType>Server</bladeType>  
  </BladeShellResponse> 
… 
- <BladeShellResponse> 
  <completionCode>Success</completionCode>  
  <statusDescription></statusDescription> 
  <apiVersion>1</apiVersion> 
  <bladeId>24</bladeId>  
  <bladeState>Fail</bladeState>  
  <bladeType>Unknown</bladeType>  



Open Compute Project  Open CloudServer OCS Chassis Management 
http://opencompute.org 117 
 
  </BladeShellResponse> 
  </bladeShellCollection> 
- <fanInfoCollection> 
- <FanInfo> 
  <completionCode>Success</completionCode>  
  <statusDescription></statusDescription> 
  <apiVersion>1</apiVersion> 
  <fanId>1</fanId>  
  <fanSpeed>4109</fanSpeed>  
  <isFanHealthy>true</ isFanHealthy >  
  </FanInfo> 
- … 
<FanInfo> 
  <completionCode>Success</completionCode>  
  <statusDescription></statusDescription> 
  <apiVersion>1</apiVersion> 
  <fanId>6</fanId>  
  <fanSpeed>4094</fanSpeed>  
  < isFanHealthy >true</ isFanHealthy >  
  </FanInfo> 
  </fanInfoCollection> 
- <psuInfoCollection> 
- <PsuInfo> 
  <completionCode>Success</completionCode>  
  <statusDescription></statusDescription> 
  <apiVersion>1</apiVersion> 
  <id>1</id>  
  <powerOut>0</powerOut>  
  <serialNumber>46-49-51-44-31-32-33-37-30-30-31-30-32-34</serialNumber>  
  <state>ON</state>  
  </PsuInfo> 
… 
- <PsuInfo> 
  <completionCode>Success</completionCode>  
  <statusDescription></statusDescription> 
  <apiVersion>1</apiVersion> 
  <id>6</id>  
  <powerOut>0</powerOut>  
  <serialNumber>46-49-51-44-31-32-33-37-30-30-31-30-35-38</serialNumber>  
  <state>ON</state>  
  </PsuInfo> 
  </psuInfoCollection> 
 
  </ChassisHealthResponse> 



 
118 October 30, 2014 
 
 
 
3.62 Get Health of Blade 
BladeHealthResponse GetBladeHealth(int bladeId, bool cpuInfo, bool memInfo, bool diskInfo, bool 
pcieInfo, bool sensorInfo, bool temp, bool fruInfo) 
https://localhost:8000/GetBladeHealth?bladeid=2&cpuInfo=true&memInfo=true&diskInfo=true&pcieInf
o=true&sensorInfo=true&temp=true&fruInfo=true 
Usage scenario: 
This API can be used for status/health monitoring of blade components such as cpu, memory, disk (JBOD 
only), pci, sensor, temperature, and FRU. 
Input parameters: 
- bladeId  
- cpuInfo 
- memInfo 
- diskInfo 
- pcieInfo 
- sensorInfo 
- temp 
- fruInfo 
Note: Except for bladeID, other parameters are optional. If none of the other parameters are specified, 
the API will fetch result for all components. 
Sample response: 
- <BladeHealthResponse 
xmlns="http://schemas.datacontract.org/2004/07/Microsoft.GFS.WCS.Contr
acts" xmlns:i="http://www.w3.org/2001/XMLSchema-instance"> 
  <completionCode>Success</completionCode>  
  <statusDescription></statusDescription> 
  <apiVersion>1</apiVersion> 
  <assetTag />  
- <bladeShell> 
  <completionCode>Success</completionCode>  
  <statusDescription></statusDescription> 
  <apiVersion>1</apiVersion> 
  <bladeId>2</bladeId>  
  <bladeState>ON</bladeState>  
  <bladeType>Server</bladeType>  
  </bladeShell> 
  <hardwareVersion>T6M</hardwareVersion>  
  <JbodDiskInfo i:nil="true" />  
  <JbodInfo i:nil="true" />  
- <memoryInfo> 
- <memoryInfo> 



Open Compute Project  Open CloudServer OCS Chassis Management 
http://opencompute.org 119 
 
  <completionCode>Success</completionCode>  
  <apiVersion>1</apiVersion> 
  <statusDescription></statusDescription> 
  <dimm>1</dimm>  
  <dimmType>DDR3</dimmType>  
  <status>Ok</status>  
  <speed>1333</speed>  
  <size>8192</size>  
  <memVoltage>1.35V</memVoltage>  
  </memoryInfo> 
- … 
- <memoryInfo> 
  <completionCode>Success</completionCode>  
  <apiVersion>1</apiVersion> 
  <statusDescription></statusDescription> 
  <dimm>2</dimm>  
  <dimmType>DDR3</dimmType>  
  <status>Ok</status>  
  <speed>1333</speed>  
  <size>8192</size>  
  <memVoltage>1.35V</memVoltage>  
  </MemoryInfo> 
… 
- <PcieInfo> 
- <PCIeInfo> 
  <completionCode>Success</completionCode>  
  <apiVersion>1</apiVersion> 
  <statusDescription></statusDescription> 
  <pcieNumber>1</pcieNumber>  
  <vendorId>0x0000</vendorId>  
  <deviceId>0x0000</deviceId>  
  <subSystemId>0x00000000</subSystemId>  
  <status>NotPresent</status>  
  </PCIeInfo> 
- <PCIeInfo> 
  <completionCode>Success</completionCode>  
  <apiVersion>1</apiVersion> 
  <statusDescription></statusDescription> 
  <pcieNumber>2</pcieNumber>  
  <vendorId>0x15B3</vendorId>  
  <deviceId>0x1003</deviceId>  
  <subSystemId>0x8995152D</subSystemId>  
  <status>Present</status>  
  </PCIeInfo> 
- <processorInfo> 
- <processorInfo> 



 
120 October 30, 2014 
 
  <completionCode>Failure</completionCode>  
  <statusDescription>Device did not return result</statusDescription> 
  <apiVersion>1</apiVersion> 
  <frequency>0</frequency>  
  <procId>0</procId>  
  <procType i:nil="true" />  
  <state i:nil="true" />  
  </processorInfo> 
  <productType />  
  <sensors />  
  <serialNumber>QTFCTM2350003</serialNumber>  
  </BladeHealthResponse> 
6.6.62 Get Next Boot Device 
BootResponse GetNextBoot(int bladeId) 
https://localhost:8000/GetNextBoot?bladeid=2 
Usage scenario: 
This API gets the boot device of the blade after the next reboot. 
 
This command does not reflect the BIOS boot order.  The SetNextboot command acts as an interrupt 
before the BIOS boot order is initialized. If the SetNextBoot order is flagged with persistence it interrupts 
boot every time, until manual user intervention to change the BIOS manually (then the SetNextBoot is 
overridden and must be executed again). If it is not flagged with persistence the command will do a 1 
time volatile override (if you hard power cycle volatile memory is lost, hence it needs to be a BMC 
power cycle). 
Input parameters: 
bladeId  
Sample response: 
<BootResponse 
xmlns="http://schemas.datacontract.org/2004/07/Microsoft.GFS.WCS.Contr
acts" xmlns:i="http://www.w3.org/2001/XMLSchema-instance"> 
  <completionCode>Success</completionCode>  
  <statusDescription></statusDescription> 
  <apiVersion>1</apiVersion> 
  <nextBootString>NoOverRide</nextBootString>  
  </BootResponse> 
6.6.63 Set Next Boot Device 
BootResponse SetNextBoot(int bladeId, BladeBootType bootType, bool uefi, bool persistent, int 
bootInstance) 
https://localhost:8000/SetNextBoot?bladeid=2&bootType=2&uefi=false&persistent=false 



Open Compute Project  Open CloudServer OCS Chassis Management 
http://opencompute.org 121 
 
 
Usage scenario: 
This API sets the boot device of the blade upon its next reboot. The boot device can be set using the 
bootType parameter from the list of devices specified in the enum below.  
 
This command does not change the BIOS boot order; itd acts as an interrupt before the BIOS boot order 
is initialized. If the SetNextBoot order is flagged with persistence it interrupts boot every time, until 
manual user intervention to change the BIOS manually (then the SetNextBoot is overridden and must be 
executed again). If it is not flagged with persistence the command will do a one-time volatile override (if 
you hard power cycle volatile memory is lost, hence it needs to be a BMC power cycle). 
 
    /// <summary> 
    /// Boot type for blades.  
    /// The boot should follow soon (within one minute) after the boot type is set. 
    /// </summary> 
    public enum BladeBootType : int 
    { 
        Unknown = 0, 
        NoOverride = 1, 
        ForcePxe = 2, 
        ForceDefaultHdd = 3, 
        ForceIntoBiosSetup = 4, 
        ForceFloppyOrRemovable = 5 
    }  
- Input Parameters:bladeId  
- bootType: type of the boot device 
- uefi: true sets UEFI BIOS, false sets legacy BIOS 
- persistent: true sets it for all subsequent reboots, false sets it just for the next reboot 
bootInstance: the instance of the boot device (for example, the second NIC card) 
Sample response: 
<BootResponse 
xmlns="http://schemas.datacontract.org/2004/07/Microsoft.GFS.WCS.Contracts" 
xmlns:i="http://www.w3.org/2001/XMLSchema-instance"> 
  <completionCode>Success</completionCode>  
  <statusDescription></statusDescription> 
  <apiVersion>1</apiVersion> 
  <nextBootString>ForcePxe</nextBootString>  
  </BootResponse> 
6.6.64 Get Service Version 
ServiceVersionResponse GetServiceVersion() 
https://localhost:8000/GetServiceVersion? 
Usage scenario: 
This API gets the version information for Chassis Manager service.  
Here the service version contains the following four values: 



 
122 October 30, 2014 
 
  Major Version 
  Minor Version  
  Build Number 
  Revision 
 
    /// <summary> 
    /// Service version information 
    /// </summary> 
    [DataContract] 
    public class ServiceVersionResponse : ChassisResponse 
    { 
        [DataMember] 
        public string serviceVersion; 
           } 
Sample response: 
<ServiceVersionResponse 
xmlns="http://schemas.datacontract.org/2004/07/Microsoft.GFS.WCS.Contracts" 
xmlns:i="http://www.w3.org/2001/XMLSchema-instance"> 
  <completionCode>Success</completionCode>  
  <statusDescription></statusDescription> 
  <apiVersion>1</apiVersion> 
  <serviceVersion>1.2.0.0</serviceVersion>  
  </ServiceVersionResponse> 
 
6.6.65 Reset PSU 
ChassisResponse ResetPsu(int pusId) 
https://localhost:8000/ResetPsu?psuId=1 
Usage scenario:  
This API turns the power supply off, and then on again.  
Input parameters: 
 psuId 
6.6.66 Get Chassis Manager Asset Info 
ChassisAssetInfoResponse GetChassisManagerAssetInfo() 
https://localhost:8000/GetChassisManagerAssetInfo 
Usage scenario:  



Open Compute Project  Open CloudServer OCS Chassis Management 
http://opencompute.org 123 
 
This API gets the FRU information of the Chassis Manager. 
Input parameters: 
 None 
6.6.67 Get Power Distribution Board (PDB) Asset Info 
ChassisAssetInfoResponse GetPDBAssetInfo () 
https://localhost:8000/GetPDBAssetInfo 
Usage Scenario:  
This API gets the FRU information of the power distribution board (PDB). 
Input parameters: 
 None 
6.6.68 Get Blade Asset Info 
BladeAssetInfoResponse GetBladeAssetInfo(int bladeId) 
https://localhost:8000/ GetBladeAssetInfo?bladeId=1 
Usage scenario:  
This API gets the FRU information of the specified blade. 
Input parameters: 
 bladeId (blade index 1-48) 
Sample response 
<?xml version="1.0"?> 
-<BladeAssetInfoResponse 
xmlns="http://schemas.datacontract.org/2004/07/Microsoft.GFS.WCS.Contracts" 
xmlns:i="http://www.w3.org/2001/XMLSchema-
instance"><completionCode>Success</completionCode><apiVersion>1</apiVersion><statusDescription
/><bladeNumber>2</bladeNumber><chassisAreaPartNumber>X873021-
001</chassisAreaPartNumber><chassisAreaSerialNumber>QTFCTM2490136</chassisAreaSerialNumber
><boardAreaManufacturerName>Microsoft</boardAreaManufacturerName><boardAreaManufacturer
Date>12/6/2012 10:36:00 AM</boardAreaManufacturerDate><boardAreaProductName>WCS SB 
EN</boardAreaProductName><boardAreaSerialNumber>MH824800046</boardAreaSerialNumber><bo
ardAreaPartNumber>X873096-
001</boardAreaPartNumber><productAreaManufactureName>Microsoft</productAreaManufactureNa
me><productAreaProductName>WCS 
Mt.Glacier</productAreaProductName><productAreaPartModelNumber>X873095-



 
124 October 30, 2014 
 
001</productAreaPartModelNumber><productAreaProductVersion>1.0</productAreaProductVersion>
<productAreaSerialNumber>MH824800046</productAreaSerialNumber><productAreaAssetTag>N/A</
productAreaAssetTag><manufacturer/><multiRecordFields 
xmlns:a="http://schemas.microsoft.com/2003/10/Serialization/Arrays"/></BladeAssetInfoResponse> 
6.6.69 Set Chassis Manager Asset Info 
MultiRecordResponse SetChassisManagerAssetInfo(string payLoad) 
https://localhost:8000/ SetChassisManagerAssetInfo?payLoad=X 
Usage scenario:  
This API sets the FRU Multi Record Area information for the Chassis Manager with the user specified 
record data. 
Input parameters: 
 payLoad (user specified data).  
Note: For payload, user can enter it as multiple fields (each representing a Multi Record FRU 
field), each separated by comma. As part of the specification, the user can only enter maximum 
2 fields, where each field can be of maximum 56 bytes (characters) length. 
6.6.70 Set PDB Asset Info 
MultiRecordResponse SetPDBAssetInfo(string payLoad) 
https://localhost:8000/ SetPDBAssetInfo?payLoad=X 
Usage scenario:  
This API sets the FRU Multi Record Area information for the power distribution board (PDB) with the 
user specified record data. 
Input parameters: 
 payLoad (user specified data) 
Note: For payload, user can enter it as multiple fields (each representing a Multi Record FRU 
field), each separated by comma. As part of the specification, the user can only enter maximum 
two fields, where each field can be of maximum 56 bytes (characters) length. 
6.6.71 Set Blade Asset Info 
MultiRecordResponse SetBladeAssetInfo(int bladeId) 



Open Compute Project  Open CloudServer OCS Chassis Management 
http://opencompute.org 125 
 
https://localhost:8000/ SetBladeAssetInfo?bladeId=1&payLoad=xxxxx 
Usage scenario:  
This API sets the FRU Multi Record Area information with the user specified data for the blade with the 
specified index. 
Input parameters: 
 bladeId (blade index 1-48) 
 payLoad (user specified data) 
Note: For payload, user can enter it as multiple fields (each representing a Multi Record FRU 
field), each separated by comma. As part of the specification, the user can only enter maximum 
2 fields, where each field can be of maximum 56 bytes (characters) length.  
6.6.72 Get Blade Post Code 
BiosPostCode GetPostCode(int bladeId) 
https://localhost:8000/GetPostCode?bladeId=1 
Usage scenario:  
This API gets the post code for the blade with specified blade id. 
Input parameters: 
 bladeId (blade index 1-48) 
6.6.73 Update PSU Firmware 
ChassisResponse UpdatePSUFirmware(int psuId, string fwFilepath, bool primaryImage) 
https://localhost:8000/UpdatePSUFirmware?psuId=1&fwFilepath=c:\<user>\630_002279_0000 
_MS1425W_SecWithBootloader_CSE76E_V021700.hex&primaryImage=false 
Usage scenario: 
This API updates the firmware of the primary or secondary controller of the power supply unit (PSU). 
When a firmware update is initiated, the PSU will shut off its output power. The Chassis Manager will 
also stop monitoring the PSU that is being updated.  
Since firmware update takes approximately 11 minutes for the primary controller, and 9 minutes for the 
secondary controller, the update process should only be performed while AC power is supplied to the 
PSU.  
Once firmware update is initiated on a primary or secondary controller, the firmware update must 
complete successfully before updating the other controller. For example, if firmware update is initiated 
but failed for any reason on the secondary controller, the firmware update must be executed again on 



 
126 October 30, 2014 
 
the secondary controller until it completes successfully. 
Use the GetPSUFirmwareStatus API to check the status of the firmware update. 
Input parameters: 
 psuId – the target PSU number to update.Typically 1-6 
 fwFilepath – path to firmware image file 
 primaryImage – true: firmware image file is for primary controller. False: firmware image file is 
for secondary controller 
6.6.74 Get PSU Firmware Update Status 
PsuFirmwareStatus GetPSUFirmwareStatus(int psuId) 
https://localhost:8000/GetPSUFirmwareStatus?psuId=1 
Usage scenario: 
This API gets the firmware revision, overall firmware update status and the progress stage of the 
firmware update.  
 
7 Command Line Interface 
The CLI is intended for service technicians or testers who need quick access to the Chassis Manager 
services and capabilities without having to use a browser or write a REST client. 
7.1 Install the Chassis Manager Service 
Table 46 lists the commands to install, start, stop, and uninstall the Chassis Manager service and to 
launch the command-line interface. 
Table 46: Commands to install Chassis Manager service and launch the CLI 
Action Command 
Install service 
CM-Binary-Directory> 
C:\Windows\Microsoft.NET\Framework\v4.0.30319\InstallUtil.exe 
Microsoft.GFS.WCS.ChassisManager.exe 
Start service net start chassismanager 
Stop service net stop chassismanager 



Open Compute Project  Open CloudServer OCS Chassis Management 
http://opencompute.org 127 
 
Action Command 
Uninstall 
service 
CM-Binary-Directory> 
C:\Windows\Microsoft.NET\Framework\v4.0.30319\InstallUtil.exe /u 
Microsoft.GFS.WCS.ChassisManager.exe 
Launch CLI 
WcsCli-Binary-Directory> wcscli  –h <hostname>  -p <port>  -s<SSL encryption option> 
[[-u] <username> [-x] <password>] [-b <batch_file_name>] 
-h <hostname>  
Host name of computer on which the Chassis Manager service is running 
-p <port>  
Port on which Chassis Manager Service is listening (It is usually 8000) 
-s  
<SSL encryption option>  
 Select 0- To disable SSL encryption. 
 Select 1-To enabled SSL encryption. 
-u and -x   
Optional parameters, user credentials (username(-u) and password(-x)) to connect to 
CM service. If not specified default credentials are used. 
B<Batch file name>  
Optional argument, use to execute commands from a batch file. 
Note that host name, port, and SSL encryption options are mandatory and should be 
supplied to launch the CLI. 
Get CLI Version 
WcsCli-Binary-Directory> wcscli –v 
Returns the current CLI version. 
7.2 State and Information Commands 
The sections that follow describe the ACS system CLI commands, which provide information about 
the system state. 
7.2.1 GetChassisInfo 
Description:  
This command gets status information about chassis components including the following: 
Blades – for example, GUID and power status  
Power supplies – for example, power draw  status and serial number 
Chassis Manager – version information, IP information, and system uptime  
The power supply status is not available during a PSU firmware upgrade process. 



 
128 October 30, 2014 
 
Syntax: 
wcscli –getchassisinfo [-s] [-p] [-c] [-t] [-h] 
-s – Show information about blades  
-p – Show information about power supplies  
-c – Show Chassis Manager information 
-h – Help, display the correct syntax 
Sample usage: 
wcscli#  wcscli –s –p –c -t 
Sample output: 
== Compute Nodes == 
#       | Name  | GUID     | State | BMC MAC       | Completion Code 
1       | BLADE1        | 71cd4e40-a900-11e1-9856-089e013a37e8  | On    | 
DeviceID: 0MAC Address: 08:9E:01:22:FB:42     | Success 
2       | BLADE2        | 590fbcc0-a910-11e1-b117-089e013a37f8  | On    | 
DeviceID: 0MAC Address: 08:9E:01:22:FB:32     | Success 
3       | BLADE3        | b56945e0-a93d-11e1-be83-089e013a3809  | On    | 
DeviceID: 0MAC Address: 08:9E:01:22:FB:3E     | Success 
4       | BLADE4        | 9f7f0a40-a83d-11e1-a8ad-089e013a3798  | On    | 
DeviceID: 0MAC Address:  
08:9E:01:29:60:32     | Success 
5       | BLADE5        | ae7ee0a0-d50c-11e1-b27d-089e015a2876  | On    | 
DeviceID: 0MAC Address: 08:9E:01:5A:2C:16     | Success 
6       | BLADE6        | 506d99c0-d4fd-11e1-b020-089e015a2872  | On    | 
DeviceID: 0MAC Address: 08:9E:01:5A:2C:1C     | Success 
7       | BLADE7        | 07c79a60-d505-11e1-a944-089e015a2874  | On    | 
DeviceID: 0MAC Address: 08:9E:01:5A:2C:0A     | Success 
8       | BLADE8        | 7b7398a0-d4e8-11e1-aa7a-089e015a286c  | On    | 
DeviceID: 0MAC Address: 08:9E:01:5A:2C:18     | Success 
9       | BLADE9        | 3d54f900-d4df-11e1-a52d-089e015a286a  | On    | 
DeviceID: 0MAC Address: 08:9E:01:5A:2C:1E     | Success 
10      | BLADE10       | dcfaf040-d4f3-11e1-8ce3-089e015a2870  | On    | 
DeviceID: 0MAC Address: 08:9E:01:5A:2C:40     | Success 
…..... 
== Power Supplies == 
#       | Serial Num    | State | Pout (W)      | Completion Code 
1       | 46-49-51-44-31-32-33-37-30-30-31-31-32-33     | On    | 194   | 
Success 
2       | 46-49-51-44-31-32-33-37-30-30-31-31-32-38     | On    | 228   | 
Success 
3       | 46-49-51-44-31-32-33-37-30-30-31-30-36-30     | On    | 190   | 
Success 
4       | 46-49-51-44-31-32-33-37-30-30-31-30-38-33     | On    | 214   | 
Success 
5       | 46-49-51-44-31-32-33-37-30-30-31-30-33-30     | On    | 188   | 
Success 
6       | 46-49-51-44-31-32-33-37-30-30-31-30-32-39     | On    | 203   | 
Success 
 
== Chassis Controller == 
Firmware Version        : 02.02 



Open Compute Project  Open CloudServer OCS Chassis Management 
http://opencompute.org 129 
 
Hardware Version        : 1 
Serial Number           : 33333333 
Asset Tag               : 
IP Address              : 192.168.100.23 
IP Address Source       : 192.168.100.8 
System Uptime           : 00:21:32.5127429 
7.2.2 GetBladeInfo 
Description:  
This command gets information about the blades, including serial number and version information. 
Syntax: 
wcscli -getbladeinfo [ -i <blade_index> | -a ] [-h] 
-i – Blade index (1-24)  
-a – Get information for all blades  
-h – Help, display the correct syntax 
Sample usage: 
To get information on blade 1, execute the following command: 
WcsCli# wcscli -getbladeinfo -i 2 
Sample output: 
== Compute Node Info == 
Firmware Version        : 03.02 
Hardware Version        : T6M 
Serial Number           : QTFCTM2350005 
Asset Tag               : 
 
== MAC Address == 
Device Id                       : 0 
MAC Address             : 08:9E:01:22:FB:32 
7.2.3 GetChassisHealth 
Description:  
This command gets health status for blades, power supplies, and fans. The power supply status is not 
available during a PSU firmware upgrade process. 
Syntax: 
wcscli -getchassishealth [-b] [-p] [-f] [-t] [-h] 
-b – Show blade health  
-p – Show PSU health 
-f – Show fan health 
 



 
130 October 30, 2014 
 
-h – Help, display the correct syntax 
Sample usage: 
To get information about blade 1, execute the following command: 
wcscli# wcscli –getchassishealth –b –p –f  
Sample output: 
== Blade Health == 
Blade Id        : 1 
Blade State     : ON 
Blade Type      : Server 
 
Blade Id        : 2 
Blade State     : ON 
Blade Type      : Server 
 
Blade Id        : 3 
Blade State     : ON 
Blade Type      : Server 
 
Blade Id        : 4 
Blade State     : OFF 
Blade Type      : Server 
 
Blade Id        : 5 
Blade State     : ON 
Blade Type      : Unknown 
 
Blade Id        : 6 
Blade State     : ON 
Blade Type      : Unknown 
…… 
………. 
== PSU Health == 
Psu Id  : 1 
Psu Serial Number       : 46-49-51-44-31-32-33-37-30-30-31-3 
Psu State               : ON 
PSU Power Out           : 0 
Psu Completion code: Success 
 



Open Compute Project  Open CloudServer OCS Chassis Management 
http://opencompute.org 131 
 
Psu Id  : 2 
Psu Serial Number       : 46-49-51-44-31-32-33-37-30-30-31-3 
Psu State               : ON 
PSU Power Out           : 0 
Psu Completion code: Success 
 
Psu Id  : 3 
Psu Serial Number       : 46-49-51-44-31-32-33-37-30-30-31-3 
Psu State               : ON 
PSU Power Out           : 0 
Psu Completion code: Success 
 
Psu Id  : 4 
Psu Serial Number       : 46-49-51-44-31-32-33-37-30-30-31-3 
Psu State               : ON 
PSU Power Out           : 0 
Psu Completion code: Success 
 
Psu Id  : 5 
Psu Serial Number       : 46-49-51-44-31-32-33-37-30-30-31-3 
Psu State               : ON 
PSU Power Out           : 0 
Psu Completion code: Success 
 
Psu Id  : 6 
Psu Serial Number       : 46-49-51-44-31-32-33-37-30-30-31-3 
Psu State               : ON 
PSU Power Out           : 0 
Psu Completion code: Success 
 
 
== Fan Health == 
Fan Id  : 1 
Fan Speed: 3670 
Fan status: ON 
 
Fan Id  : 2 
Fan Speed: 3683 
Fan status: ON 
 



 
132 October 30, 2014 
 
Fan Id  : 3 
Fan Speed: 3474 
Fan status: ON 
 
Fan Id  : 4 
Fan Speed: 3468 
Fan status: ON 
 
Fan Id  : 5 
Fan Speed: 3633 
Fan status: ON 
 
Fan Id  : 6 
Fan Speed: 3571 
Fan status: ON 
7.2.4 GetBladeHealth 
Description:  
This command gets health information about the blade, including CPU, memory, disk (JBOD only), PCIe, 
sensor, and FRU information. The information can be requested separately using specific command 
options. 
Syntax: 
wcscli -getbladehealth [-i <blade_index>] [-q] [-m] [-d] [-p] [-s] [-t] [-
f] [-h] 
-q – Show blade CPU information  
-m – Show blade memory information 
-d – Show JBOD disk information 
-p – Show blade PCIe information 
-s – Show blade sensor information 
-t – Show temperature sensor information 
-f – Show blade FRU information 
-h – Help, display the correct syntax 
Sample usage: 
To get information on blade 1, execute the following command: 
wcscli# wcscli –getbladehealth –i 1  
Sample output: 
== Blade 2 Health Information == 
Blade ID        : 2 
Blade State     : ON 
Blade Type      : Server 



Open Compute Project  Open CloudServer OCS Chassis Management 
http://opencompute.org 133 
 
 
== Memory Information == 
Dimm            : 1 
Dimm Type       : DDR3 
Memory Voltage  : 1.35V 
Size            : 16384 
Speed           : 1333 
Memory Status   : Ok 
Memory Completion code: Success 
 
Dimm            : 2 
Dimm Type       : NotPresent 
Memory Voltage  : NotPresent 
Size            : 0 
Speed           : 0 
Memory Status   : NotPresent 
Memory Completion code: Success 
 
Dimm            : 3 
Dimm Type       : DDR3 
Memory Voltage  : 1.35V 
Size            : 16384 
Speed           : 1333 
Memory Status   : Ok 
Memory Completion code: Success 
 
== PCIE Information == 
Dimm            : 1 
Dimm Type       : DDR3 
Memory Voltage  : 1.35V 
Size            : 16384 
Speed           : 1333 
Memory Status   : Ok 
Memory Completion code: Success 
 
Dimm            : 2 
Dimm Type       : NotPresent 
Memory Voltage  : NotPresent 
Size            : 0 
Speed           : 0 



 
134 October 30, 2014 
 
Memory Status   : NotPresent 
Memory Completion code: Success 
 
Dimm            : 3 
Dimm Type       : DDR3 
Memory Voltage  : 1.35V 
Size            : 16384 
Speed           : 1333 
Memory Status   : Ok 
Memory Completion code: Success 
 
== FRU Information == 
Blade Serial Number     : QTFCTM2370293 
Blade Asset Tag : 
Blade Product Type      : 
Blade Hardware Version  : T6M 
Note that some of the fields populated are blank as complete FRU data is not available for the on which 
the sample command was executed. 
7.2.5 GetServiceVersion 
Description:  
This command gets Chassis Manager service assembly version.  
Syntax: 
wcscli -getserviceversion [-h] 
-h – Help, display the correct syntax 
Sample usage: 
To get information on blade 1, execute the following command: 
wcscli# wcscli -getserviceversion  
Sample output: 
Chassis Manager Service version: 1.2.0.0 
 
7.2.6 Update PSU Firmware 
Description:  
This command updates the firmware of the primary or secondary controller of the power supply unit 
(PSU). When a firmware update is initiated, the PSU will shut off its output power. The Chassis Manager 



Open Compute Project  Open CloudServer OCS Chassis Management 
http://opencompute.org 135 
 
will also stop monitoring the PSU that is being updated.  
Since firmware update takes approximately 11 minutes for the primary controller, and 9 minutes for the 
secondary controller, the update process should only be performed while AC power is supplied to the 
PSU.  
Once firmware update is initiated on a primary or secondary controller, the firmware update must 
complete successfully before updating the other controller. For example, if firmware update is initiated 
but failed for any reason on the secondary controller, the firmware update must be executed again on 
the secondary controller until it completes successfully. 
Use the getpsufwstatus command to check the status of the firmware update.  
Syntax: 
wcscli -updatepsufw [-i <psuId>] [-f <filePath>] [-
p <isPrimaryImage>]  [-h] 
        psuId - the target PSU number to update. Typically 1-6 
        -f - path to firmware image file 
        -p - 1: Firmware image file is for primary controller. 
             0: Firmware image file is for secondary controller. 
        -h - help; display the correct syntax 
 
Sample usage: 
To update the secondary controller on PSU 1, execute the following command: 
wcscli# wcscli –updatepsufw -i 1 –f c:\<user>\630_002279_0000 
_MS1425W_SecWithBootloader_CSE76E_V021700.hex –p 0 
Sample output: 
OK. Use wcscli -getpsufwstatus to check the status of the firmware update. 
7.2.7 Get PSU Firmware Update Status 
Description:  
This command gets the firmware revision, overall firmware update status and the progress stage of the 
firmware update. 
Syntax: 
wcscli -getpsufwstatus [-i <psuId>] [-h] 
        psuId - the target PSU number. Typically 1-6 
        -h - help; display the correct syntax 
 
Sample usage: 
To get the firmware update status on PSU 1, execute the following command: 
wcscli# wcscli –getpsufwstatus -i 1 
 



 
136 October 30, 2014 
 
Sample output: 
== PSU Firmware Status == 
Firmware Revision       : D1.11.11 
Firmware Update Status  : NotStarted 
Firmware Update Stage   : NotStarted 
Completion Code         : Success 
 
7.3 Blade Management Commands 
The sections that follow describe the ACS system CLI blade management commands. 
7.3.1 SetPowerOn 
Description:  
This command turns the AC outlet power ON for the blade. 
When AC power gets supplied to the blade and the default blade power state is set to ON, the blade 
chipset will start to receive power and boot process will be initiated. If the default blade power state is 
set to OFF when AC power is applied, the blade chipset will not receive power (and the boot process will 
not be initiated). You can explicitly send a SetBladeOn command to power the blade on. 
Syntax: 
wcscli –setpoweron [-i <blade_index> | -a] [-h] 
-i – Blade index (1-24)  
-a – Get information for all blades 
-h – Help, display the correct syntax 
Sample usage: 
To turn the power ON on blade 3, use the following command: 
wcscli#  wcscli –setpoweron –i 3 
Sample output: 
OK 
7.3.2 SetPowerOff 
Description:  
This command turns the AC outlet power OFF for the blades. 
Syntax: 
wcscli –setpoweroff [-i <blade_index> | -a] [-h] 
-i – Blade index (1-24)  
-a – Get information for all blades 
-h – Help, display the correct syntax 



Open Compute Project  Open CloudServer OCS Chassis Management 
http://opencompute.org 137 
 
Sample usage: 
To turn the power OFF on blade 3, use the following command: 
wcscli#  wcscli –setpoweroff –i 3 
Sample output: 
OK 
7.3.3 GetPowerState 
Description:  
This command gets the AC outlet power ON/OFF state of blades (whether or not the blades are 
receiving AC power). 
 When ON, blade is receiving AC power (hard power state).  
 When OFF, blade is not receiving AC power. 
Syntax: 
wcscli –getpowerstate [-i <blade_index> | -a] [-h] 
-i – Blade index (1-24)  
-a – Get information for all blades 
-h – Help, display the correct syntax 
Sample usage: 
To get the power state for blade 1, use the following command: 
wcscli#  wcscli –getpowerstate –i 1 
Sample output: 
Blade 5: On 
7.3.4 SetBladeOn 
Description:  
This command supplies the power to the blade chipset, initializing the boot process. This command is 
used to soft power the blade ON. 
Syntax: 
wcscli –setbladeon [ -i <blade_index> | -a] [-h] 
-i – Blade index (1-24)  
-a – All connected blades 
-h – Help, display the correct syntax 
Sample usage: 
To soft power ON blade 1, use the following command: 
wcscli#  wcscli –setbladeon –i 1 
Sample output: 
Blade 1: ON 



 
138 October 30, 2014 
 
7.3.5 SetBladeOff 
Description:  
This command removes the power from the blade chipset. This command is used to soft power the 
blade OFF. 
Syntax: 
wcscli –setbladeoff [[-i <blade_index>] |[-a]] [-h] 
-i – Blade index (1-48)  
-a – All connected blades 
-h – Help, display the correct syntax 
Sample usage: 
To soft power OFF blade 1, use the following command: 
wcscli#  wcscli –setbladeoff –i 1 
Sample output: 
Blade 1: OFF 
7.3.6 GetBladeState 
Description:  
This command gets the ON/OFF state of the blade (whether the blade chipset is receiving power).  
 When ON, blade is receiving AC power (hard power state) and the chipset is receiving power 
(soft power state).  
 When OFF, blade chipset is not receiving power. 
Syntax: 
wcscli –getbladestate [[-i <blade_index>] | [-a]] [-h] 
-i – Blade index (1-24)  
-a – All connected blades 
-h – Help, display the correct syntax 
Sample usage: 
To get the ON/OFF state of blade 1, use the following command: 
wcscli#  wcscli –getbladestate –i 1 
Sample output: 
Blade State 1: ON 
7.3.7 SetBladeDefaultPowerState 
Description:  
This command sets the default power state of the blade ON/OFF.  
The default blade power state denotes the behavior of the blade after receiving AC power, either when 
a blade is initially inserted in to its slot or power returns after a utility failure. If the blade default power 



Open Compute Project  Open CloudServer OCS Chassis Management 
http://opencompute.org 139 
 
state is set to OFF, the blade won’t be powered ON after receiving AC input power. An explicit 
SetBladeOn command needs to be sent to power ON the blade. If the blade default power state is set to 
ON, the blade will be powered ON after receiving AC input power. 
Note that the blade default power state does not affect the active power state of the blade, only their 
behaviors after a hard power recycle. 
Syntax: 
wcscli –setbladedefaultpowerstate [[-i <blade_index>] | [-a] ] -s 
<state>[-h] 
-i – Blade index (1-24)  
-a – All connected blades 
-s – State, can be 0 (stay OFF) or 1 (power ON) 
-h – Help, display the correct syntax 
Sample usage: 
To set the default power state of of blade 1 to ON, use the following command: 
wcscli#  wcscli –setbladedefaultpowerstate –i 1 -s 1 
Sample output: 
Blade 1 Default Power State: ON 
7.3.8 GetBladeDefaultPowerState 
Description:  
This command gets the default power state of the blade ON/OFF.  
Syntax: 
wcscli –getbladedefaultpowerstate [[-i <blade_index>] | [-a]][-h] 
-i – Blade index, the number of blades (1-24)  
-a – Gets information for all blades 
-h – Help, display the correct syntax 
Sample usage: 
To set the default power state of of blade 1 to ON, use the following command: 
wcscli#  wcscli –getbladedefaultpowerstate –i 1 
Sample output: 
Blade 1 Default Power State: ON 
7.3.9 SetBladeActivePowerCycle 
Description:  
This command power cycles or soft resets the blade(s).  
Power cycle resets the blade (causing a software reboot sequence).  Blade AC power signal remains ON 
throughout this process. Any serial session active on that blade will continue to be active during this 
process. 



 
140 October 30, 2014 
 
Syntax: 
wcscli –setbladeactivepowercycle [[-i <blade_index>]| [-a]] | [-t 
<off_time>][-h] 
-i – Blade index, the number of blades (1-24)  
-a – Gets information for all blades 
-t – Indicates the power off time, i.e., the time interval in seconds for how long the blade stays OFF 
before the power is again turned on. If not specified, the default interval is 0 seconds. 
-h – Help, display the correct syntax 
Sample usage: 
To power cycle blade 3, use the following command: 
wcscli#  wcscli –setbladeactivepowercycle –i 3 
Sample output: 
OK 
7.3.10 SetBladeAttentionLEDOn 
Description:  
This command turns the blade attention LED On. The purpose of this attention LED is to indicate that 
this blade needs attention. The command can also be used to identify the blade. 
The blade attention LED is used to help service technicians find the blade during repair. Users can also 
flag a service requirement by turning ON this LED. Operators/users must ensure that the blade attention 
LED is turned OFF after service is complete. 
Syntax: 
wcscli –setbladeattentionledon [[-i <blade_index>]| [-a]][-h] 
-i – Blade index, the number of blades (1-24)  
-a – Gets information for all blades 
-h – Help, display the correct syntax 
Sample usage: 
To turn the blade attention LED for blade 1 ON, use the following command: 
wcscli#  wcscli –setbladeattentionledon –i 1 
Sample output: 
OK 
7.3.11 SetBladeAttentionLEDOff 
Description:  
This command turns the blade attention LED Off. The purpose of this attention LED is to indicate that 
this blade needs attention.  
The blade attention LED is used to help service technicians find the blade during repair. Users can also 
flag a service requirement by turning ON this LED. Operators/users must ensure that the blade attention 



Open Compute Project  Open CloudServer OCS Chassis Management 
http://opencompute.org 141 
 
LED is turned OFF after service is complete. 
Syntax: 
wcscli –setbladeattentionledoff [[-i <blade_index>]|[-a]][-h] 
-i – Blade index, the number of blades (1-24)  
-a – Gets information for all blades 
-h – Help, display the correct syntax 
Sample usage: 
To turn the blade attention LED for blade 1 OFF, use the following command: 
wcscli#  wcscli –setbladeattentionledoff –i 1 
Sample output: 
OK 
7.3.12 ReadBladeLog 
Description:  
This command reads the log from a blade.  The blade log (system event log) contains information about 
events/warnings/alerts pertaining to that blade like thermal throttling of blades due to overheating, etc. 
Syntax: 
wcscli –readbladelog [-i <blade_index>] [-n <entries_count>] [-h] 
-i – Blade index, the number of blades (1-24)  
-n – How many of the most recent entries to report. This is an optional parameter; if not specified the 
command will return all existing entries. 
-h – Help, display the correct syntax 
Sample usage: 
To read the blade log for blade 1, use the following command: 
wcscli#  wcscli –readbladelog –i 1 
Sample output: 
#       | EventTime   |    EventDescription                            
    
| 2012-08-23T14:35:21| Sensor_SpecificDrive_Slot2433328Assertion111    
| 2012-08-23T16:11:08| DiscreteTemperature187257Desertion3    
| 2012-08-23T18:35:21| Sensor_SpecificDrive_Slot2463328Assertion111 
| 2012-08-23T19:35:21| Sensor_SpecificDrive_Slot2433328Assertion111    
| 2012-08-23T20:35:21| Sensor_SpecificDrive_Slot2433328Assertion111 
7.3.13 ClearBladeLog 
Description:  
This command clears the log from a blade. 
Syntax: 
wcscli –clearbladelog [-i <blade_index>] [-h] 



 
142 October 30, 2014 
 
-i – Blade index, the number of blades (1-24)  
-h – Help, display the correct syntax 
Sample usage: 
To clear the blade log for blade 1, use the following command: 
wcscli#  wcscli –clearbladelog –i 1  
Sample output: 
OK 
7.3.14 SetBladePowerLimit 
Description:  
This command sets the power limit for a blade. 
The power limit can be set for a variety of reasons including energy savings and under provisioning 
(consolidate more servers under a power hierarchy). 
The minimum and maximum power limits are specified in the Chassis Manager app.config file. 
Syntax: 
wcscli –setbladepowerlimit [[-i <blade_index>] | [-a ]] -l <power_limit> 
[-h] 
-i – Blade index, the number of blades (1-24)  
-a – Perform action for all blades  
-l – Blade power limit, in W  
-h – Help, display the correct syntax 
Sample usage: 
To set the power limit for blade 1 to 750 W, use the following command: 
wcscli#  wcscli –setbladepowerlimit –i 1 –l 750   
Sample output: 
Blade 1 power limit: 750 Watts 
7.3.15 SetBladePowerLimitOn 
Description:  
This command activates the power limit for a blade, and enables power throttling. 
Syntax: 
wcscli –setbladepowerlimiton [[-i <blade_index>]|[-a]] [-h] 
-i – Blade index, the number of blades (1-24)  
-a – Perform action for all blades  
-h – Help, display the correct syntax 
Sample usage: 
To activates the power limit for blade 1, use the following command: 



Open Compute Project  Open CloudServer OCS Chassis Management 
http://opencompute.org 143 
 
wcscli#  wcscli –setbladepowerlimiton –i 1  
Sample output: 
Blade 1: ON 
7.3.16 SetBladePowerLimitOff 
Description:  
This command deactivates the power limit for a blade, and disables power throttling. 
Syntax: 
wcscli –setbladepowerlimitoff [[-i <blade_index>]|[-a]] [-h] 
-i – Blade index, the number of blades (1-24)  
-a – Perform action for all blades  
-h – Help, display the correct syntax 
Sample usage: 
To deactivates the power limit for blade 1, use the following command: 
wcscli#  wcscli –setbladepowerlimitoff –i 1  
Sample output: 
Blade 1: OFF 
7.3.17 GetBladePowerLimit 
Description:  
This command gets the power limit for a blade. 
Syntax: 
wcscli –getbladepowerlimit [[-i <blade_index>]|[-a]] [-h] 
-i – Blade index, the number of blades (1-24)  
-a – Perform action for all blades  
-h – Help, display the correct syntax 
Sample usage: 
To get the power limit for blade 1, use the following command: 
wcscli#  wcscli –getbladepowerlimit –i 1    
Sample output: 
Blade 1 power limit 750 Watts 
7.3.18 GetBladePowerReading 
Description:  
This command gets the power reading for a blade. The command can be used for monitoring and or 
other power control mechanism (refer to the SetBladePowerLimit command). 
Syntax: 



 
144 October 30, 2014 
 
wcscli –getbladepowerreading [[-i <blade_index>]|[-a]] [-h] 
-i – Blade index, the number of blades (1-24)  
-a – Perform action for all blades  
-h – Help, display the correct syntax 
Sample usage: 
To get the power reading for blade 1, use the following command: 
wcscli#  wcscli –getbladepowerreading –i 1    
Sample output: 
Blade 1 power reading: 67 Watts 
7.3.19 GetNextBoot 
Description:  
This command gets the pending boot order to be applied the next time the blade boots.  
Once the boot order is applied, GetNextBoot will return the default value of NoOverRide. 
Syntax: 
wcscli –getnextboot [-i <blade_index>][-h] 
-i – Blade index, the number of blades (1-24)  
-h – Help, display the correct syntax 
Sample usage: 
To get the next boot device type for blade 1, use the following command: 
wcscli#  wcscli –getnextboot –i 1    
Sample output: 
OK. Next boot is ForcePxe. 
7.3.20 SetNextBoot 
Description:  
This command sets the device boot type of the start boot device during the subsequent reboot for a 
blade. 
Syntax: 
wcscli –setbootnext [-i <blade_index>] [-t <boot_type>] [-m <boot_mode>][-
p <is_persistent>] [-n <boot_instance>] [-h] 
-i – Blade index (1-24)  
boot_type – One of the following: 
1. NoOverRide 
2. ForcePxe 
3. ForceDefaultHdd,  
4. ForceIntoBiosSetup 
5. ForceFloppyOrRemovable 



Open Compute Project  Open CloudServer OCS Chassis Management 
http://opencompute.org 145 
 
 
boot_mode - boolean (0 or 1) indicating whether the next boot is wanted to be in UEFI mode (or legacy 
mode) 
is_persistent – Is this a persistent setting (set value 1) or a one-time setting (set value 0) 
boot_instance – instance number of the boot device (for example, 0 or 1 for NIC if there are two NICs) 
-h – Help, display the correct syntax 
Sample usage: 
To set the boot device for blade 1, use the following command: 
wcscli#  wcscli –setnextboot –i 2 –p 1 -m 1 –n 1 
Sample output: 
OK. Next boot is ForceDefaultHdd 
7.3.21 GetBladeAssetInfo 
Description:  
This command gets the FRU information of the specified blade. 
Syntax: 
wcscli –getbladeassetinfo [-i <blade_index>][-h] 
-i – Blade index (1-24)  
-h – Help, display the correct syntax 
Sample usage: 
To get the asset (FRU) information for blade 1, use the following command: 
wcscli#  wcscli –getbladeassetinfo –i 1  
Sample output: 
-------------------------------------- 
Blade Chassis Info Area 
-------------------------------------- 
Chassis Part Number = X898637-001 
Chassis Serial Number = QTFCLJ4150005 
-------------------------------------- 
 
Blade Board Info Area 
-------------------------------------- 
Board Manufacturer Name = Microsoft 
Board Manufacturer Date = 4/8/2014 8:18:00 AM 
Board Product Name = C1030Q 
Board Serial Number = ALJ41300232 
Board Part Number = X898568-001 
-------------------------------------- 
 
Blade Product Info Area 
-------------------------------------- 
Product Manufacturer Name = Microsoft 
Product Product Name = C1030Q 



 
146 October 30, 2014 
 
Product Part/Model Number = X892646-001 
Product Version = 2.0 
Product Serial Number = QTFCLJ4150005 
PD Product Asset Tag = 
-------------------------------------- 
 
Multi Record Info Area 
-------------------------------------- 
Manufacturer = 
Custom Fields 
 
7.3.22 SetBladeAssetInfo 
Description:  
This command is used to edit the Multi Record Area FRU information of the specified blade. 
Syntax: 
wcscli –setbladeassetinfo [-i <blade_index>] [-p <payload>][-h] 
-i – Blade index (1-24)  
-p – data to be written to Chassis Manager FRU Multi Record Area  
-h – Help, display the correct syntax 
 
Note: 
For payload, user can enter it as multiple fields (each representing a Multi Record FRU field), each 
separated by comma. As part of the specification, the user can only enter maximum 2 fields, where each 
field can be of maximum 56 bytes (characters) length.  
Sample usage: 
To set the asset (FRU) information for blade 1, use the following command: 
wcscli#  wcscli –setbladeassetinfo –i 1 -p TEST 
Sample output: 
Command Success: Blade 1 Blade’s FRU has been written successfully 
7.3.23 GetPDBAssetInfo 
Description:  
This command gets the FRU information of the PDB. 
Syntax: 
wcscli –getpdbassetinfo [-h] 
-h – Help, display the correct syntax 
Sample usage: 
To get the asset (FRU) information for the PDB, use the following command: 



Open Compute Project  Open CloudServer OCS Chassis Management 
http://opencompute.org 147 
 
wcscli#  wcscli –getpdbassetinfo  
Sample output: 
-------------------------------------- 
Power Distribution Board (PDB) Chassis Info Area 
-------------------------------------- 
Chassis Part Number = 
Chassis Serial Number = 
-------------------------------------- 
 
Power Distribution Board (PDB) Board Info Area 
-------------------------------------- 
Board Manufacturer Name = 
Board Manufacturer Date = 1/1/1996 12:00:00 AM 
Board Product Name = 
Board Serial Number = 
Board Part Number = 
-------------------------------------- 
 
Power Distribution Board (PDB) Product Info Area 
-------------------------------------- 
Product Manufacturer Name = 
Product Product Name = 
Product Part/Model Number = 
Product Version = 
Product Serial Number = 
PD Product Asset Tag = 
-------------------------------------- 
 
Power Distribution Board (PDB) Multi Record Info Area 
-------------------------------------- 
Manufacturer = 
Custom Fields 
 
7.3.24 SetPDBAssetInfo 
Description:  
This command is used to edit the Multi Record Area FRU information of the specified blade. 
Syntax: 
wcscli –setpdbassetinfo [-p <payload>][-h] 
-p – data to be written to PDB FRU Multi Record Area 
-h – Help, display the correct syntax 
Sample usage: 
To set the asset (FRU) information for PDB, use the following command: 
wcscli#  wcscli –setpdbassetinfo -p TEST 
Note: 
For payload, user can enter it as multiple fields (each representing a Multi Record FRU field), each 



 
148 October 30, 2014 
 
separated by comma. As part of the specification, the user can only enter maximum 2 fields, where each 
field can be of maximum 56 bytes (characters) length.  
Sample output: 
PDB's FRU has been written successfully 
7.3.25 GetBladeBIOSPostCode  
Description:  
This command gets the post code for the blade with specified blade id. 
Syntax: 
wcscli -getbladebiospostcode [-i <blade_index> [-h] 
blade_index - the target blade number. Typically 1-24 
-h - help; display the correct syntax 
Sample usage: 
Wcscli # wcscli –getbladebiospostcode –i 1 
 
7.4 Chassis Manager Management Commands 
The sections that follow describe the ACS system CLI Chassis Manager management commands. 
7.4.1 SetChassisAttentionLEDOn 
Description:  
This command turns the Chassis attention LED On. The purpose of this attention LED is to indicate that 
this Chassis Manager needs attention.  
The chassis attention LED is used to direct service technicians to the correct chassis during repair. Users 
can also flag a service requirement by turning ON this LED. When possible, repairs will also be self-
directed by the chassis management system. Operators/users must ensure that the Chassis Attention 
LED is turned OFF after service is complete. 
Syntax: 
wcscli –setchassisattentionledon [-h] 
-h – Help, display the correct syntax 
Sample usage: 
To turn the chassis attention LED ON, use the following command: 
wcscli#  wcscli –setchassisattentionledon 
Sample output: 
OK 



Open Compute Project  Open CloudServer OCS Chassis Management 
http://opencompute.org 149 
 
7.4.2 SetChassisAttentionLEDOff 
Description:  
This command turns the Chassis attention LED Off. The purpose of this attention LED is to indicate that 
this Chassis Manager needs attention.  
The chassis attention LED is used to direct service technicians to the correct chassis during repair. Users 
can also flag a service requirement by turning ON this LED. When possible, repairs will also be self-
directed by the chassis management system. Operators/users must ensure that the Chassis Attention 
LED is turned OFF after service is complete. 
Syntax: 
wcscli –setchassisattentionledoff [-h] 
-h – Help, display the correct syntax 
Sample usage: 
To turn the chassis attention LED OFF, use the following command: 
wcscli#  wcscli –setchassisattentionledoff 
Sample output: 
OK 
7.4.3 GetChassisAttentionLEDStatus 
Description:  
This command gets the status of the chassis attention LED (whether ON or OFF).  
The chassis attention LED is used to direct service technicians to the correct chassis during repair. Users 
can also flag a service requirement by turning ON this LED. When possible, repairs will also be self-
directed by the chassis management system. Operators/users must ensure that the Chassis Attention 
LED is turned OFF after service is complete. 
Syntax: 
wcscli –getchassisattentionledstatus [-h] 
-h – Help, display the correct syntax 
Sample usage: 
To get the status of the chassis attention LED, use the following command: 
wcscli#  wcscli –getchassisattentionledstatus 
Sample output: 
Chassis LED: OFF 
7.4.4 ReadChassisLog 
Description:  
This command reads the chassis log. 
The chassis log contains information about various alerts/warning messages associated with devices 



 
150 October 30, 2014 
 
connected to the Chassis Manager (for example, blade overheating or fan/PSU failure). 
The chassis log also contains user audit information, such as timestamp/activity performed by that user. 
Syntax: 
wcscli -readchassislog [-s <startDate>] [-e <endDate>] [-h] 
-s - Optional start date for the log entries (format: YYYY:MM:DD) 
-e - Optional end date for the log entries (format: YYYY:MM:DD) 
-h - help; display the correct syntax 
Sample usage: 
To get the chassis user log, use the following command: 
wcscli#  wcscli –readchassislog 
 
Sample output: 
== Chassis Controller Log == 
Timestamp       | Entry 
10/3/2012 3:22:56 PM    | <user>,Invoked 
GetChassisInfo(True,True,True) 
10/3/2012 3:22:57 PM    | <user>,Invoked GetBladeState(bladeid: 1) 
10/3/2012 3:22:57 PM    | <user>,Invoked GetBladeState(bladeid: 2) 
10/3/2012 3:22:57 PM    | <user>,Invoked GetBladeState(bladeid: 3) 
10/3/2012 3:22:58 PM    | <user>,Invoked 
GetChassisNetworkProperties() 
10/3/2012 3:23:45 PM    | <user>,Invoked ReadBladelog(bladeId: 1) 
7.4.5 ClearChassisLog 
Description:  
This command clears the chassis log. 
To comply with size restrictions on Chassis Manager storage space, users are expected to periodically 
clear the consumed log entries. 
Syntax: 
wcscli –clearchassislog [-h] 
-h – Help, display the correct syntax 
Sample usage: 
To clear the chassis user log, use the following command: 
wcscli#  wcscli –clearchassislog 



Open Compute Project  Open CloudServer OCS Chassis Management 
http://opencompute.org 151 
 
Sample output: 
OK 
7.4.6 GetACSocketPowerState 
Description:  
This command gets the status of chassis AC sockets (TOR switches). 
The AC socket power state refers to active power state of the COM ports (and therefore to the power 
state of the device connected to the port) on the Chassis Manager. For example, the TOR switch is 
connected to COM1 (port number 1). The power ON/OFF commands for the AC sockets makes it 
possible to remotely power-reset the device and also for enabling/disabling purpose. 
Syntax: 
wcscli –getacsocketpowerstate -p <port_no> [-h] 
-p – Port number of interest 
-h – Help, display the correct syntax 
Sample usage: 
To get the status of the chassis AC sockets for port 2, use the following command: 
wcscli#  wcscli –getacsocketpowerstate –p 2 
Sample output: 
ON 
7.4.7 SetACSocketPowerStateOn 
Description:  
This command turns the chassis AC sockets (TOR switches) ON. 
The AC socket power state refers to active power state of the COM ports (and therefore to the power 
state of the device connected to the port) on the Chassis Manager. For example, the TOR switch is 
connected to COM1 (port number 1). The power ON/OFF commands for the AC sockets makes it 
possible to remotely power-reset the device and also for enabling/disabling purpose. 
Syntax: 
wcscli –setacsocketpowerstateon -p <port_no> [-h] 
-p – Port number of interest 
-h – Help, display the correct syntax 
Sample usage: 
To turn ON the chassis AC sockets for port 12, use the following command: 
wcscli#  wcscli –setacsocketpowerstateon –p 12 
Sample output: 
OK 



 
152 October 30, 2014 
 
7.4.8 SetACSocketPowerStateOff 
Description:  
This command turns the chassis AC sockets (TOR switches) OFF. 
The AC socket power state refers to active power state of the COM ports (and therefore to the power 
state of the device connected to the port) on the Chassis Manager. For example, the TOR switch is 
connected to COM1 (port number 1). The power ON/OFF commands for the AC sockets makes it 
possible to remotely power-reset the device and also for enabling/disabling purpose. 
Syntax: 
wcscli –setacsocketpowerstateoff -p <port_no> [-h] 
-p – Port number of interest 
-h – Help, display the correct syntax 
Sample usage: 
To turn OFF the chassis AC sockets for port 12, use the following command: 
wcscli#  wcscli –setacsocketpowerstateoff –p 12 
Sample output: 
OK 
7.4.9 AddChassisControllerUser 
Description:  
This command adds a new chassis controller user with specified password and WCS security role for 
accessing the Chassis Manager command-line interface. The role should be Admin, Operator, or User. 
Each role has access to a specific set of APIs. 
Syntax: 
wcscli –adduser –u <username> -p <password> -a|-o|-r [-h] 
-u username – Username for the new user 
-p password – Password for the new user 
Select one of the WCS security roles for the user (mandatory): 
-a – Admin privilege 
-o – Operator privilege 
-r–  User privilege 
-h – Help, display the correct syntax 
Sample usage: 
To add a user with admin privileges, use the following command: 
wcscli#  wcscli –adduser –u myname –p pass!123 -a 
Sample output: 
OK 



Open Compute Project  Open CloudServer OCS Chassis Management 
http://opencompute.org 153 
 
7.4.10 ChangeChassisControllerUserPassword 
Description:  
This command changes the password for an existing user in the chassis controller. 
Syntax: 
wcscli –changeuserpwd –u <username> -p <newpassword> [-h] 
-u username – Username for which the password will be changed 
-p newpassword – new password for the user 
-h – Help, display the correct syntax 
Sample usage: 
To add a user with admin privileges, use the following command: 
wcscli#  wcscli –changeuserpwd –u myname  –p pa##!143 
Sample output: 
OK 
7.4.11 ChangeChassisControllerUserRole 
Description:  
This command changes the WCS security role for an existing user in the chassis controller.  
Note that the user will be removed from other WCS security roles and added to the new role specified. 
Users can belong to only one security role. 
Syntax: 
wcscli –changeuserrole –u <username> -a|-o|-r [-h] 
-u username – Username for the new user 
Select one of the WCS security roles for the user (mandatory): 
-a – Admin privilege 
-o – Operator privilege 
-r – User privilege 
-h – Help, display the correct syntax 
Sample usage: 
To change the user role to operator, use the following command: 
wcscli#  wcscli -changeuserrole –u myname  –o 
Sample output: 
OK 
7.4.12 RemoveChassisControllerUser 
Description:  
This command removes an existing user from the chassis controller. 
Syntax: 



 
154 October 30, 2014 
 
wcscli –removeuser –u <username>[-h] 
-u username – Username for the new user 
-h – Help, display the correct syntax 
Sample usage: 
To remove a user, use the following command: 
wcscli#  wcscli -removeuser –u myname  
Sample output: 
OK 
7.4.13 GetChassisManagerAssetInfo 
Description:  
This command gets the FRU information of the Chassis Manager. 
Syntax: 
wcscli –getbladeassetinfo[-h] 
-h – Help, display the correct syntax 
Sample usage: 
To get the asset (FRU) information for the Chassis Manager, use the following command: 
wcscli#  wcscli –getchassismanagerassetinfo  
Sample output: 
 -------------------------------------- 
Chassis Manager Chassis Info Area 
-------------------------------------- 
Chassis Part Number = X873021-001 
Chassis Serial Number = 0000000000000000 
-------------------------------------- 
Chassis Manager Board Info Area 
-------------------------------------- 
Board Manufacturer Name = Microsoft 
Board Manufacturer Date = 3/3/2014 12:52:00 AM 
Board Product Name = E1000 
Board Serial Number = NH840800124 
Board Part Number = X873064-001 



Open Compute Project  Open CloudServer OCS Chassis Management 
http://opencompute.org 155 
 
-------------------------------------- 
Chassis Manager Product Info Area 
-------------------------------------- 
Product Manufacturer Name = Microsoft 
Product Product Name = E1000 
Product Part/Model Number = X873023-001 
Product Version = A 
Product Serial Number = NH840800124 
PD Product Asset Tag = 5892018 
-------------------------------------- 
Chassis Manager Multi Record Info Area 
-------------------------------------- 
Manufacturer = 
Custom Fields 
 
7.4.14 SetChassisManagerAssetInfo 
Description:  
This command is used to edit the Multi Record Area FRU information of the Chassis Manager. 
Syntax: 
wcscli –setbladeassetinfo [-p <payload>][-h] 
-p – data to be written to Chassis Manager FRU Multi Record Area 
-h – Help, display the correct syntax 
Note: 
For payload, user can enter it as multiple fields (each representing a Multi Record FRU field), each 
separated by comma. As part of the specification, the user can only enter maximum 2 fields, where each 
field can be of maximum 56 bytes (characters) length.  
Sample usage: 
To set the asset (FRU) information for the Chassis Manager, use the following command: 
wcscli#  wcscli –setchassismanagerassetinfo -p TEST 
Sample output: 
Chassis Manager's FRU has been written successfully 
 



 
156 October 30, 2014 
 
7.5 Blade and Serial Console Session Commands 
The sections that follow describe the ACS system CLI blade and serial console session commands. 
7.5.1 StartBladeSerialSession 
Description: 
This command is used to start serial session to a blade. The command will open a Serial-Client-terminal 
for the serial session. 
Users might want to open a serial session to a blade for debugging purposes, to view blade boot 
messages, or for executing BIOS commands. A VT100 console will be provided that will continuously poll 
the blade for any serial session data. Any user command entered using the VT100 console will be sent to 
the blade. 
Note that this session might close unexpectedly if there is a simultaneous IPMI command issued to any 
of the chassis blades or because to inactivity of more than five minutes.  
In order to avoid the user screen from being overlapped with the incoming content from the serial 
session,  it’s recommended to clear the screen first before establishing a serial session with a blade. 
Syntax: 
wcscli -startbladeserialsession [-i <blade_index>] [-s 
<session_timeout_in_secs>] [-h] 
blade_index - the number of the blade. Typically 1-24 
-s Session timeout in seconds 
-h - help; display the correct syntax 
Sample usage: 
To start a serial session to the blade, use the following command: 
wcscli# wcscli –startbladeserialsession -i blade_index 
Sample Output: 
This opens a VT100 session for that blade. 
7.5.2 StopBladeSerialSession 
Description: 
This command is used to force the termination of any active serial session to any blade and for any 
‘KillSerialConsoleSession’ App.config parameter value. 
Chassis Manager service exposes a config. parameter called ‘KillSerialConsoleSession’ in its App.config 
file. The default value of this parameter is 1, which means that an incoming IPMI command will 
terminate an existing blade serial console session, allowing the incoming command to proceed (default 
behavior). A value of 0 implies that an incoming IPMI command will be ignored (fail) and an already 
existing blade serial session will not be interrupted. This is a configurable parameter which can be 
adjusted based on specific use case scenario.  Note that in order to change this configuration value, the 
ChassisManager service must first be stopped. The configuration file is locked while the service is 
running. 



Open Compute Project  Open CloudServer OCS Chassis Management 
http://opencompute.org 157 
 
 
Syntax: 
wcscli -stopbladeserialsession [-h] 
-h - help; display the correct syntax 
Sample usage: 
To stop a serial session to the blade, use the following command: 
wcscli# wcscli –stopbladeserialsession 
Sample Output: 
The serial console session to the given blade will be terminated and control returns to WCSCLI prompt. 
7.5.3 StartPortSerialSession 
Description: 
This command is used to open a serial port console terminal to serial devices that are connected to the 
Chassis Manager (for example, Top of Rack (TOR) network switches). Session timeout and device 
timeout can be specified as input, if not specified default timeout values (two minutes for session 
timeout and 100ms for device timeout) from service config are used for the session. Only ports 1 
(COM1) and 2 (COM2) connections from the Chassis Manager are supported. 
In order to avoid the user screen from being overlapped with the incoming content from the serial 
session, it is recommended to clear the screen first before establishing a serial session. 
Syntax:  
wcscli -startportserialsession [-i <Port_index>][-s 
<session_timeout_in_secs>] [-d <device_timeout_in_millisecs>] 
[-r <baud_rate> (75,110,300,1200,2400,4800,9600,19200,38400,57600,115200)][-h] 
-i Port number. The number of the COM port the device is connected to. Enter 1 for COM1, 2 for COM2. 
-s Session timeout in secs, 
-d Device timeout in millisecs 
-r Baud rate 
-h - Help; display the correct syntax 
Sample usage: 
To to start serial port consolel, use the following command: 
wcscli# wcscli –startportserialsession -i port_index –s 120 –d 100 
Sample output: 
This opens VT100 session for the serial port console. 
7.5.4 StopPortSerialSession 
Description: 
Stop all existing sessions on given port. 
Syntax:  
wcscli -stopPortSerialSession [-i <Port_index> [-h] 
-i Port number 
-h - Help; display the correct syntax 



 
158 October 30, 2014 
 
Sample usage: 
To to start serial port consolel, use the following command: 
wcscli# wcscli –stopPortSerialSession -i port_number 
Sample output: 
All existing sessions ended. 
7.5.5 EstablishCmConnection 
Description: 
Create a connection to the Chassis Manager service.  
Make sure ‘local echo’ is enabled when connection to CM is established using this command. Otherwise, 
the commands typed by the user won’t be visible on the terminal. 
Syntax:  
wcscli establishCmConnection -m <host_name> -p <port> -s <SSL_option> [-u] 
<username> [-x] <password> [-b] <batchfileName> [-h] 
-m host_name - Specify Host name for Chassis manager (for serial 
connection, localhost is assumed) 
-p port - Specify a valid Port to connect to for Chassis Manager (default 
is 8000) 
-s Select Chassis Manager (CM)'s SSL Encryption mode (enabled/disabled?)  
Enter 0 if CM is not configured to use SSL encrytion (SSL disabled in CM) 
Enter 1 if CM requires SSl Encryption (SSL enabled in CM) 
-u & -x specify user credentials -- username and password -- to connect to 
CM service (Optional.. will use default credentials) 
-b Optional batch file option (not supported in serial mode). 
-v Get CLI version information 
-h help 
 
Sample usage: 
To establish a connection to the Chassis Manager, use the following command: 
wcscli# wcscli –establishCmConnection -p 8000 -s 0 -u username -x password 
Sample output: 
Connection to CM succeeded.. 



Open Compute Project  Open CloudServer OCS Chassis Management 
http://opencompute.org 159 
 
7.5.6 TerminateCmConnection 
Description: 
Terminate a connection to the Chassis Manager service. 
Syntax:  
wcscli terminateCmConnection [-h] 
-h help 
 
Sample usage: 
To terminate a connection to the Chassis Manager, use the following command: 
wcscli# wcscli –terminateCmConnection 
Sample output: 
Connection to CM terminated successfully. 
7.6 CLI Over Serial (WCSCLI+) 
Note that these commands are available in WCSCLI Serial mode only. Otherwise, all these 
commands will fail with the following console message: 
Command only supported in serial wcscli client mode. 
7.6.1 StartChassisManager 
Description: 
This command is used to start serial Windows Chassis Manager service. 
 Syntax: 
wcscli -startchassismanager [-h] 
-h - help; display the correct syntax 
Sample usage: 
To start the Windows Chassis Manager service, use the following command: 
wcscli# wcscli –startchassismanager 
Sample Output: 
Chassis Manager successfully started. 
7.6.2 StopChassisManager 
Description: 
This command is used to stop an existing Windows Chassis Manager service.  
Syntax:  
wcscli -stopchassismanager [-h] 
-h - Help; display the correct syntax 



 
160 October 30, 2014 
 
Sample usage: 
To stop Windows Chassis Manager service, use the following command: 
wcscli# wcscli –stopchassismanager 
Sample output: 
Chassis manager service successfully stopped. 
7.6.3 GetChassisManagerStatus 
Description: 
Get the status of Windows Chassis Manager service. 
Syntax:  
wcscli -getchassismanagerstatus [-h] 
-h - Help; display the correct syntax 
Sample usage: 
To get the status of Chassis Manager service, use the following command: 
wcscli# wcscli –getchassismanagerstatus 
Sample output: 
chassismanager service status: Running 
OK 
7.6.4 EnableChassisManagerSsl 
Description: 
Enable SSL for the Chassis Manager service. 
Syntax:  
wcscli -enablechassismanagerssl [-h] 
-h - Help; display the correct syntax 
Sample usage: 
To enable SSL for the Chassis Manager service, use the following command: 
wcscli# wcscli –enablechassismanagerssl 
Sample output: 
Successfully enabled SSL in the chassismanager service. 
You will need to establish connection to the CM again via establishCmConnection command to run any 
commands. 
wcscli -establishCmConnection -m <host_name> -p <port> -s <SSL_option> [-u] <username> [-x] 
<password> [-b] <batchfileName> 
-m host_name - Specify Host name for Chassis manager (for serial connection, localhost is assumed) 
-p port - Specify a valid Port to connect to for Chassis Manager (default is 8000) 
-s Select Chassis Manager (CM)'s SSL Encryption mode (enabled/disabled?)  



Open Compute Project  Open CloudServer OCS Chassis Management 
http://opencompute.org 161 
 
Enter 0 if CM is not configured to use SSL encrytion (SSL disabled in CM) 
Enter 1 if CM requires SSl Encryption (SSL enabled in CM) 
-u & -x specify user credentials -- username and password -- to connect to CM service (Optional.. will use 
default credentials) 
-b Optional batch file option (not supported in serial mode). 
-v Get CLI version information 
-h help 
7.6.5 DisableChassisManagerSsl 
Description: 
Disable SSL for the Chassis Manager service. 
Syntax:  
wcscli -disablechassismanagerssl [-h] 
-h - Help; display the correct syntax 
Sample usage: 
To disable SSL for the Chassis Manager service, use the following command: 
wcscli# wcscli –disablechassismanagerssl 
Sample output: 
Successfully disabled SSL in the chassismanager service. 
You will need to establish connection to the CM again via establishCmConnection command to run any 
commands. 
wcscli -establishCmConnection -m <host_name> -p <port> -s <SSL_option> [-u] <username> [-x] 
<password> [-b] <batchfileName> 
-m host_name - Specify Host name for Chassis manager (for serial connection, localhost is assumed) 
-p port - Specify a valid Port to connect to for Chassis Manager (default is 8000) 
-s Select Chassis Manager (CM)'s SSL Encryption mode (enabled/disabled?)  
Enter 0 if CM is not configured to use SSL encrytion (SSL disabled in CM) 
Enter 1 if CM requires SSl Encryption (SSL enabled in CM) 
-u & -x specify user credentials -- username and password -- to connect to CM service (Optional.. will use 
default credentials) 
-b Optional batch file option (not supported in serial mode). 
-v Get CLI version information 
-h help 
7.6.6 GetNetworkProperties (getnic) 
Description:  
This command gets the chassis controller network properties. 
Syntax: 
wcscli –getnic[-h] 



 
162 October 30, 2014 
 
Note that when reading the NIC settings, in DHCP mode, all old NIC settings for the subnet mask, 
gateway IP and DNS servers will be returned by Windows through WMI. 
-h – Help, display the correct syntax 
Sample usage: 
To get the network configuration details for the chassis, use the following command: 
wcscli#  wcscli -getnic  
Sample output: 
N/W Interface 0: 
        Index                   : 10 
        Description             : Intel(R) 82574L Gigabit Network 
Connection 
        ServiceName             : e1iexpress 
        MAC Address             : 08:9E:01:6C:24:1B 
        IP Enabled              : True 
        DHCP Enabled            : False 
        DHCP Server             : 
        IP Address              : {192.168.150.56, 
fe80::8533:7d05:79b4:8895} 
        Subnet Mask             : {255.255.0.0, 64} 
        Gateway Address         : {124.55.22.33} 
        DNS Servers             : 
        DNS Hostname            : CMPVT10 
        DNS Domain              : 
        WINS Primary            : 
        WINS Secondary          : 
        Completion Code         : Success 
 
7.6.7 SetNetworkProperties (setnic) 
Description:  
This command sets the chassis controller network properties (only available over serial wcscli client). 
Syntax: 
wcscli -setnic [-a] <IP addr source DHCP/STATIC -Required!> [-i] <IP 
address (Required for Static IP)> [-m] <subnetmask (Required for Static 
IP)> [-g] <gateway> [-p] <primary DNS> [-d] <secondary DNS> [-t] <network 
interface number> [-h]  
        -a - IP addr source DHCP/Static 
        -i - IP address of the chassis controller (Required for Static IP. Not used for DHCP.) 
        -m - subnet mask of the chassis controller (Required for Static IP. Not used for DHCP.) 
        -g - gateway of the chassis controller (Optional for Static IP. Not used for DHCP.). Note that the 
gateway IP can be cleared by switching to DHCP and then back to static IP. 
        -p - primary DNS server address for the chassis controller (Optional) 
        -d - secondary DNS server address for the chassis controller (Optional. Only valid if primary DNS is 
also specified.) 



Open Compute Project  Open CloudServer OCS Chassis Management 
http://opencompute.org 163 
 
        -t - network interface controller number to configure (0-index. Optional). Default to 0 if not 
specified 
        -h – help; display the correct syntax 
Sample usage: 
To set the network configuration for the chassis, use the following command: 
wcscli#  wcscli -setnic -m 255.255.0.0 -i 10.160.148.220 -p 10.160.148.220 
-d 127.0.0.1 -a static -t 0 
Sample output: 
The command will execute successfully, and there will be intermittent connection loss to Chassis 
Manager because of the network config. update. 
7.6.8 Clear 
Description: 
This command allows user to clear previously entered commands from history. Also clears the PuTTY 
client screen. 
 
Syntax:  
wcscli -clear [-h] 
-h - Help; display the correct syntax 
Sample usage: 
To clear command history, use the following command: 
wcscli# wcscli –clear 
Sample output: 
Clear command history cache and clears the display screen on client window, displaying the CLI prompt. 
 
7.7 PuTTY Settings for serial connection 
The recommended and supported tool for the CLI via serial connection is PuTTY.  
This section describes the settings required for PuTTY. 
1.) Set the assigned COM port baud rate to (115200), as shown in Figure 14.  
Note: COM port designations on your configuration may differ from this. 



 
164 October 30, 2014 
 
Figure 14: Set assigned baud rate 
 


Open Compute Project  Open CloudServer OCS Chassis Management 
http://opencompute.org 165 
 
2.) Set terminal settings to local echo off and local line editing off, as shown in Figure 15. This allows 
the application to perform echo and line editing. 
Figure 15: Set terminal settings 
 
 


 
166 October 30, 2014 
 
3.) Set the Keyboard to VT100+ and Backspace to be ‘Control-?(127)’, as shown in Figure 16. 
Figure 16: Set keyboard and backspace settings 
 
 


Open Compute Project  Open CloudServer OCS Chassis Management 
http://opencompute.org 167 
 
4.) Set the window size to default 80 characters and select forbid resizing option, as shown in 
Figure 17. This allows the PuTTY session output to match the command console output. 
Figure 17: Set window size 
 
 


 
168 October 30, 2014 
 
5.) Save these settings to be loaded for future use and open the connection, as shown in Figure 18. 
Figure 18: Save settings 
 
7.8 Service Install 
This section describes the various steps (see below) required to install the WcsCli service: 
1. Create two folders under the C: drive. The folders can be named something like “WcsCliCOM5” 
and “WcsCliCOM6”. 
2. Copy the new WcsCli binaries under each of the two created folders in step 1.  
 Inside each of these directories, there is a file of type Config called “WcsCli.exe”. Make 
sure you change the “COMPortName” key’s value to the desired COM port to which the 
service attaches in that config. file. For example, for WcsCliCOM5 folder, update the 
WcsCli.exe config. file by changing the COMPortName to COM5. 
3. Open a CMD prompt as “Administrator”. 
4. Navigate to each of the the two newly created folders. 
5. Run"“C:\Windows\Microsoft.NET\Framework\v4.0.30319\InstallUtil.exe WcsCli.exe”. 
6. Run “Net start WCSCLI<COMPortName>.” 


Open Compute Project  Open CloudServer OCS Chassis Management 
http://opencompute.org 169 
 
7. Run “Services.msc” which will show the list of services and their statuses. You should see 
WcsCliCOM5 and WcsCliCOM6 listed as services. Also, you can refer to an installation log 
“WcsCli.InstallLog” that will get created under the same folder where the binaries reside. 
8. Verify that the services are correctly installed and running. You can do that by checking for an 
existing service by running the following command in a CMD prompt: 
 “sc qc <Service Name>”; where Service Name are ‘WcsCliCOM5’ and ‘WcsCliCOM6’ 
  For example,  “sc qc WcsCliCOM5” 
 
 
 
  